FILE_TYPE = MACRO_DRAWING;
SET COLOR_WIRE YELLOW;
SET COLOR_PROP MONO;
SET COLOR_DOT WHITE;
SET COLOR_ARC YELLOW;
SET COLOR_BODY GREEN;
SET COLOR_NOTE MONO;
SET PROP_DISPLAY VALUE;
SET PAGE_NUMBER P61;
FORCEADD OFFPAGE..5
(-6425 525);
FORCEPROP 2 LAST $XR1 86 
J 0
(-6769 525);
DISPLAY 0.638298 (-6769 525);
PAINT MONO (-6769 525);
FORCEPROP 2 LAST $XR0 85 
J 0
(-6679 525);
DISPLAY 0.638298 (-6679 525);
PAINT MONO (-6679 525);
FORCEPROP 2 LAST CDS_LIB mstr_standard
J 0
(-6425 525);
PAINT MONO (-6425 525);
DISPLAY INVISIBLE (-6425 525);
FORCEPROP 1 LAST OFFPAGE TRUE
J 0
(-6100 400);
DISPLAY 1.170213 (-6100 400);
PAINT GREEN (-6100 400);
DISPLAY INVISIBLE (-6100 400);
FORCEPROP 1 LAST COMMENT_BODY TRUE
J 0
(-6325 450);
DISPLAY 1.170213 (-6325 450);
PAINT GREEN (-6325 450);
DISPLAY INVISIBLE (-6325 450);
FORCEPROP 2 LAST PATH I1
J 0
(-6375 600);
DISPLAY 1.021277 (-6375 600);
PAINT ORANGE (-6375 600);
DISPLAY INVISIBLE (-6375 600);
FORCEADD TAP..6
(-5575 825);
FORCEPROP 3 LASTPIN (-5525 825) SIG_NAME M_L_CLK_DP<0>
J 0
(-5515 835);
DISPLAY 0.659574 (-5515 835);
PAINT MONO (-5515 835);
DISPLAY INVISIBLE (-5515 835);
FORCEPROP 1 LASTPIN (-5525 825) BN 0
J 0
(-5577 833);
DISPLAY 0.617021 (-5577 833);
PAINT GREEN (-5577 833);
FORCEPROP 2 LAST CDS_LIB mstr_standard
J 0
(-5575 825);
PAINT MONO (-5575 825);
DISPLAY INVISIBLE (-5575 825);
FORCEPROP 1 LAST BODY_TYPE PLUMBING
J 0
(-5575 775);
DISPLAY 1.595745 (-5575 775);
PAINT GREEN (-5575 775);
DISPLAY INVISIBLE (-5575 775);
FORCEPROP 1 LAST HDL_TAP TRUE
J 0
(-5250 700);
DISPLAY 1.595745 (-5250 700);
PAINT GREEN (-5250 700);
DISPLAY INVISIBLE (-5250 700);
FORCEPROP 1 LAST PATH I10
J 0
(-5577 825);
DISPLAY 0.872340 (-5577 825);
PAINT GREEN (-5577 825);
DISPLAY INVISIBLE (-5577 825);
FORCEADD TAP..6
R 2
(-2850 1575);
FORCEPROP 3 LASTPIN (-2900 1575) SIG_NAME M_L_ODT<3>
J 0
(-2890 1585);
DISPLAY 0.659574 (-2890 1585);
PAINT MONO (-2890 1585);
DISPLAY INVISIBLE (-2890 1585);
FORCEPROP 1 LASTPIN (-2900 1575) BN 3
J 2
(-2848 1583);
DISPLAY 0.617021 (-2848 1583);
PAINT GREEN (-2848 1583);
FORCEPROP 2 LAST CDS_LIB mstr_standard
J 0
(-2850 1575);
PAINT MONO (-2850 1575);
DISPLAY INVISIBLE (-2850 1575);
FORCEPROP 1 LAST BODY_TYPE PLUMBING
J 2
(-2850 1525);
DISPLAY 1.595745 (-2850 1525);
PAINT GREEN (-2850 1525);
DISPLAY INVISIBLE (-2850 1525);
FORCEPROP 1 LAST HDL_TAP TRUE
J 2
(-3175 1450);
DISPLAY 1.595745 (-3175 1450);
PAINT GREEN (-3175 1450);
DISPLAY INVISIBLE (-3175 1450);
FORCEPROP 1 LAST PATH I100
J 2
(-2848 1575);
DISPLAY 0.872340 (-2848 1575);
PAINT GREEN (-2848 1575);
DISPLAY INVISIBLE (-2848 1575);
FORCEADD TAP..6
R 2
(-2850 1525);
FORCEPROP 3 LASTPIN (-2900 1525) SIG_NAME M_L_ODT<2>
J 0
(-2890 1535);
DISPLAY 0.659574 (-2890 1535);
PAINT MONO (-2890 1535);
DISPLAY INVISIBLE (-2890 1535);
FORCEPROP 1 LASTPIN (-2900 1525) BN 2
J 2
(-2848 1533);
DISPLAY 0.617021 (-2848 1533);
PAINT GREEN (-2848 1533);
FORCEPROP 2 LAST CDS_LIB mstr_standard
J 0
(-2850 1525);
PAINT MONO (-2850 1525);
DISPLAY INVISIBLE (-2850 1525);
FORCEPROP 1 LAST BODY_TYPE PLUMBING
J 2
(-2850 1475);
DISPLAY 1.595745 (-2850 1475);
PAINT GREEN (-2850 1475);
DISPLAY INVISIBLE (-2850 1475);
FORCEPROP 1 LAST HDL_TAP TRUE
J 2
(-3175 1400);
DISPLAY 1.595745 (-3175 1400);
PAINT GREEN (-3175 1400);
DISPLAY INVISIBLE (-3175 1400);
FORCEPROP 1 LAST PATH I101
J 2
(-2848 1525);
DISPLAY 0.872340 (-2848 1525);
PAINT GREEN (-2848 1525);
DISPLAY INVISIBLE (-2848 1525);
FORCEADD TAP..6
R 2
(-2850 1475);
FORCEPROP 3 LASTPIN (-2900 1475) SIG_NAME M_L_ODT<1>
J 0
(-2890 1485);
DISPLAY 0.659574 (-2890 1485);
PAINT MONO (-2890 1485);
DISPLAY INVISIBLE (-2890 1485);
FORCEPROP 1 LASTPIN (-2900 1475) BN 1
J 2
(-2848 1483);
DISPLAY 0.617021 (-2848 1483);
PAINT GREEN (-2848 1483);
FORCEPROP 2 LAST CDS_LIB mstr_standard
J 0
(-2850 1475);
PAINT MONO (-2850 1475);
DISPLAY INVISIBLE (-2850 1475);
FORCEPROP 1 LAST BODY_TYPE PLUMBING
J 2
(-2850 1425);
DISPLAY 1.595745 (-2850 1425);
PAINT GREEN (-2850 1425);
DISPLAY INVISIBLE (-2850 1425);
FORCEPROP 1 LAST HDL_TAP TRUE
J 2
(-3175 1350);
DISPLAY 1.595745 (-3175 1350);
PAINT GREEN (-3175 1350);
DISPLAY INVISIBLE (-3175 1350);
FORCEPROP 1 LAST PATH I102
J 2
(-2848 1475);
DISPLAY 0.872340 (-2848 1475);
PAINT GREEN (-2848 1475);
DISPLAY INVISIBLE (-2848 1475);
FORCEADD TAP..6
R 2
(-2850 1675);
FORCEPROP 3 LASTPIN (-2900 1675) SIG_NAME M_L_CKE<0>
J 0
(-2890 1685);
DISPLAY 0.659574 (-2890 1685);
PAINT MONO (-2890 1685);
DISPLAY INVISIBLE (-2890 1685);
FORCEPROP 1 LASTPIN (-2900 1675) BN 0
J 2
(-2848 1683);
DISPLAY 0.617021 (-2848 1683);
PAINT GREEN (-2848 1683);
FORCEPROP 2 LAST CDS_LIB mstr_standard
J 0
(-2850 1675);
PAINT MONO (-2850 1675);
DISPLAY INVISIBLE (-2850 1675);
FORCEPROP 1 LAST BODY_TYPE PLUMBING
J 2
(-2850 1625);
DISPLAY 1.595745 (-2850 1625);
PAINT GREEN (-2850 1625);
DISPLAY INVISIBLE (-2850 1625);
FORCEPROP 1 LAST HDL_TAP TRUE
J 2
(-3175 1550);
DISPLAY 1.595745 (-3175 1550);
PAINT GREEN (-3175 1550);
DISPLAY INVISIBLE (-3175 1550);
FORCEPROP 1 LAST PATH I103
J 2
(-2848 1675);
DISPLAY 0.872340 (-2848 1675);
PAINT GREEN (-2848 1675);
DISPLAY INVISIBLE (-2848 1675);
FORCEADD TAP..6
R 2
(-2850 1725);
FORCEPROP 3 LASTPIN (-2900 1725) SIG_NAME M_L_CKE<1>
J 0
(-2890 1735);
DISPLAY 0.659574 (-2890 1735);
PAINT MONO (-2890 1735);
DISPLAY INVISIBLE (-2890 1735);
FORCEPROP 1 LASTPIN (-2900 1725) BN 1
J 2
(-2848 1733);
DISPLAY 0.617021 (-2848 1733);
PAINT GREEN (-2848 1733);
FORCEPROP 2 LAST CDS_LIB mstr_standard
J 0
(-2850 1725);
PAINT MONO (-2850 1725);
DISPLAY INVISIBLE (-2850 1725);
FORCEPROP 1 LAST BODY_TYPE PLUMBING
J 2
(-2850 1675);
DISPLAY 1.595745 (-2850 1675);
PAINT GREEN (-2850 1675);
DISPLAY INVISIBLE (-2850 1675);
FORCEPROP 1 LAST HDL_TAP TRUE
J 2
(-3175 1600);
DISPLAY 1.595745 (-3175 1600);
PAINT GREEN (-3175 1600);
DISPLAY INVISIBLE (-3175 1600);
FORCEPROP 1 LAST PATH I104
J 2
(-2848 1725);
DISPLAY 0.872340 (-2848 1725);
PAINT GREEN (-2848 1725);
DISPLAY INVISIBLE (-2848 1725);
FORCEADD TAP..6
R 2
(-2850 1775);
FORCEPROP 3 LASTPIN (-2900 1775) SIG_NAME M_L_CKE<2>
J 0
(-2890 1785);
DISPLAY 0.659574 (-2890 1785);
PAINT MONO (-2890 1785);
DISPLAY INVISIBLE (-2890 1785);
FORCEPROP 1 LASTPIN (-2900 1775) BN 2
J 2
(-2848 1783);
DISPLAY 0.617021 (-2848 1783);
PAINT GREEN (-2848 1783);
FORCEPROP 2 LAST CDS_LIB mstr_standard
J 0
(-2850 1775);
PAINT MONO (-2850 1775);
DISPLAY INVISIBLE (-2850 1775);
FORCEPROP 1 LAST BODY_TYPE PLUMBING
J 2
(-2850 1725);
DISPLAY 1.595745 (-2850 1725);
PAINT GREEN (-2850 1725);
DISPLAY INVISIBLE (-2850 1725);
FORCEPROP 1 LAST HDL_TAP TRUE
J 2
(-3175 1650);
DISPLAY 1.595745 (-3175 1650);
PAINT GREEN (-3175 1650);
DISPLAY INVISIBLE (-3175 1650);
FORCEPROP 1 LAST PATH I105
J 2
(-2848 1775);
DISPLAY 0.872340 (-2848 1775);
PAINT GREEN (-2848 1775);
DISPLAY INVISIBLE (-2848 1775);
FORCEADD TAP..6
R 2
(-2850 1825);
FORCEPROP 3 LASTPIN (-2900 1825) SIG_NAME M_L_CKE<3>
J 0
(-2890 1835);
DISPLAY 0.659574 (-2890 1835);
PAINT MONO (-2890 1835);
DISPLAY INVISIBLE (-2890 1835);
FORCEPROP 1 LASTPIN (-2900 1825) BN 3
J 2
(-2848 1833);
DISPLAY 0.617021 (-2848 1833);
PAINT GREEN (-2848 1833);
FORCEPROP 2 LAST CDS_LIB mstr_standard
J 0
(-2850 1825);
PAINT MONO (-2850 1825);
DISPLAY INVISIBLE (-2850 1825);
FORCEPROP 1 LAST BODY_TYPE PLUMBING
J 2
(-2850 1775);
DISPLAY 1.595745 (-2850 1775);
PAINT GREEN (-2850 1775);
DISPLAY INVISIBLE (-2850 1775);
FORCEPROP 1 LAST HDL_TAP TRUE
J 2
(-3175 1700);
DISPLAY 1.595745 (-3175 1700);
PAINT GREEN (-3175 1700);
DISPLAY INVISIBLE (-3175 1700);
FORCEPROP 1 LAST PATH I106
J 2
(-2848 1825);
DISPLAY 0.872340 (-2848 1825);
PAINT GREEN (-2848 1825);
DISPLAY INVISIBLE (-2848 1825);
FORCEADD TAP..6
R 2
(-2850 1925);
FORCEPROP 3 LASTPIN (-2900 1925) SIG_NAME M_L_MA<0>
J 0
(-2890 1935);
DISPLAY 0.659574 (-2890 1935);
PAINT MONO (-2890 1935);
DISPLAY INVISIBLE (-2890 1935);
FORCEPROP 1 LASTPIN (-2900 1925) BN 0
J 2
(-2848 1933);
DISPLAY 0.617021 (-2848 1933);
PAINT GREEN (-2848 1933);
FORCEPROP 2 LAST CDS_LIB mstr_standard
J 0
(-2850 1925);
PAINT MONO (-2850 1925);
DISPLAY INVISIBLE (-2850 1925);
FORCEPROP 1 LAST BODY_TYPE PLUMBING
J 2
(-2850 1875);
DISPLAY 1.595745 (-2850 1875);
PAINT GREEN (-2850 1875);
DISPLAY INVISIBLE (-2850 1875);
FORCEPROP 1 LAST HDL_TAP TRUE
J 2
(-3175 1800);
DISPLAY 1.595745 (-3175 1800);
PAINT GREEN (-3175 1800);
DISPLAY INVISIBLE (-3175 1800);
FORCEPROP 1 LAST PATH I107
J 2
(-2848 1925);
DISPLAY 0.872340 (-2848 1925);
PAINT GREEN (-2848 1925);
DISPLAY INVISIBLE (-2848 1925);
FORCEADD TAP..6
R 2
(-2850 1975);
FORCEPROP 3 LASTPIN (-2900 1975) SIG_NAME M_L_MA<1>
J 0
(-2890 1985);
DISPLAY 0.659574 (-2890 1985);
PAINT MONO (-2890 1985);
DISPLAY INVISIBLE (-2890 1985);
FORCEPROP 1 LASTPIN (-2900 1975) BN 1
J 2
(-2848 1983);
DISPLAY 0.617021 (-2848 1983);
PAINT GREEN (-2848 1983);
FORCEPROP 2 LAST CDS_LIB mstr_standard
J 0
(-2850 1975);
PAINT MONO (-2850 1975);
DISPLAY INVISIBLE (-2850 1975);
FORCEPROP 1 LAST BODY_TYPE PLUMBING
J 2
(-2850 1925);
DISPLAY 1.595745 (-2850 1925);
PAINT GREEN (-2850 1925);
DISPLAY INVISIBLE (-2850 1925);
FORCEPROP 1 LAST HDL_TAP TRUE
J 2
(-3175 1850);
DISPLAY 1.595745 (-3175 1850);
PAINT GREEN (-3175 1850);
DISPLAY INVISIBLE (-3175 1850);
FORCEPROP 1 LAST PATH I108
J 2
(-2848 1975);
DISPLAY 0.872340 (-2848 1975);
PAINT GREEN (-2848 1975);
DISPLAY INVISIBLE (-2848 1975);
FORCEADD TAP..6
R 2
(-2850 2075);
FORCEPROP 3 LASTPIN (-2900 2075) SIG_NAME M_L_MA<3>
J 0
(-2890 2085);
DISPLAY 0.659574 (-2890 2085);
PAINT MONO (-2890 2085);
DISPLAY INVISIBLE (-2890 2085);
FORCEPROP 1 LASTPIN (-2900 2075) BN 3
J 2
(-2848 2083);
DISPLAY 0.617021 (-2848 2083);
PAINT GREEN (-2848 2083);
FORCEPROP 2 LAST CDS_LIB mstr_standard
J 0
(-2850 2075);
PAINT MONO (-2850 2075);
DISPLAY INVISIBLE (-2850 2075);
FORCEPROP 1 LAST BODY_TYPE PLUMBING
J 2
(-2850 2025);
DISPLAY 1.595745 (-2850 2025);
PAINT GREEN (-2850 2025);
DISPLAY INVISIBLE (-2850 2025);
FORCEPROP 1 LAST HDL_TAP TRUE
J 2
(-3175 1950);
DISPLAY 1.595745 (-3175 1950);
PAINT GREEN (-3175 1950);
DISPLAY INVISIBLE (-3175 1950);
FORCEPROP 1 LAST PATH I109
J 2
(-2848 2075);
DISPLAY 0.872340 (-2848 2075);
PAINT GREEN (-2848 2075);
DISPLAY INVISIBLE (-2848 2075);
FORCEADD TAP..6
(-5575 925);
FORCEPROP 3 LASTPIN (-5525 925) SIG_NAME M_L_CLK_DP<2>
J 0
(-5515 935);
DISPLAY 0.659574 (-5515 935);
PAINT MONO (-5515 935);
DISPLAY INVISIBLE (-5515 935);
FORCEPROP 1 LASTPIN (-5525 925) BN 2
J 0
(-5577 933);
DISPLAY 0.617021 (-5577 933);
PAINT GREEN (-5577 933);
FORCEPROP 2 LAST CDS_LIB mstr_standard
J 0
(-5575 925);
PAINT MONO (-5575 925);
DISPLAY INVISIBLE (-5575 925);
FORCEPROP 1 LAST BODY_TYPE PLUMBING
J 0
(-5575 875);
DISPLAY 1.595745 (-5575 875);
PAINT GREEN (-5575 875);
DISPLAY INVISIBLE (-5575 875);
FORCEPROP 1 LAST HDL_TAP TRUE
J 0
(-5250 800);
DISPLAY 1.595745 (-5250 800);
PAINT GREEN (-5250 800);
DISPLAY INVISIBLE (-5250 800);
FORCEPROP 1 LAST PATH I11
J 0
(-5577 925);
DISPLAY 0.872340 (-5577 925);
PAINT GREEN (-5577 925);
DISPLAY INVISIBLE (-5577 925);
FORCEADD TAP..6
R 2
(-2850 2025);
FORCEPROP 3 LASTPIN (-2900 2025) SIG_NAME M_L_MA<2>
J 0
(-2890 2035);
DISPLAY 0.659574 (-2890 2035);
PAINT MONO (-2890 2035);
DISPLAY INVISIBLE (-2890 2035);
FORCEPROP 1 LASTPIN (-2900 2025) BN 2
J 2
(-2848 2033);
DISPLAY 0.617021 (-2848 2033);
PAINT GREEN (-2848 2033);
FORCEPROP 2 LAST CDS_LIB mstr_standard
J 0
(-2850 2025);
PAINT MONO (-2850 2025);
DISPLAY INVISIBLE (-2850 2025);
FORCEPROP 1 LAST BODY_TYPE PLUMBING
J 2
(-2850 1975);
DISPLAY 1.595745 (-2850 1975);
PAINT GREEN (-2850 1975);
DISPLAY INVISIBLE (-2850 1975);
FORCEPROP 1 LAST HDL_TAP TRUE
J 2
(-3175 1900);
DISPLAY 1.595745 (-3175 1900);
PAINT GREEN (-3175 1900);
DISPLAY INVISIBLE (-3175 1900);
FORCEPROP 1 LAST PATH I110
J 2
(-2848 2025);
DISPLAY 0.872340 (-2848 2025);
PAINT GREEN (-2848 2025);
DISPLAY INVISIBLE (-2848 2025);
FORCEADD TAP..6
R 2
(-2850 2125);
FORCEPROP 3 LASTPIN (-2900 2125) SIG_NAME M_L_MA<4>
J 0
(-2890 2135);
DISPLAY 0.659574 (-2890 2135);
PAINT MONO (-2890 2135);
DISPLAY INVISIBLE (-2890 2135);
FORCEPROP 1 LASTPIN (-2900 2125) BN 4
J 2
(-2848 2133);
DISPLAY 0.617021 (-2848 2133);
PAINT GREEN (-2848 2133);
FORCEPROP 2 LAST CDS_LIB mstr_standard
J 0
(-2850 2125);
PAINT MONO (-2850 2125);
DISPLAY INVISIBLE (-2850 2125);
FORCEPROP 1 LAST BODY_TYPE PLUMBING
J 2
(-2850 2075);
DISPLAY 1.595745 (-2850 2075);
PAINT GREEN (-2850 2075);
DISPLAY INVISIBLE (-2850 2075);
FORCEPROP 1 LAST HDL_TAP TRUE
J 2
(-3175 2000);
DISPLAY 1.595745 (-3175 2000);
PAINT GREEN (-3175 2000);
DISPLAY INVISIBLE (-3175 2000);
FORCEPROP 1 LAST PATH I111
J 2
(-2848 2125);
DISPLAY 0.872340 (-2848 2125);
PAINT GREEN (-2848 2125);
DISPLAY INVISIBLE (-2848 2125);
FORCEADD TAP..6
R 2
(-2850 2175);
FORCEPROP 3 LASTPIN (-2900 2175) SIG_NAME M_L_MA<5>
J 0
(-2890 2185);
DISPLAY 0.659574 (-2890 2185);
PAINT MONO (-2890 2185);
DISPLAY INVISIBLE (-2890 2185);
FORCEPROP 1 LASTPIN (-2900 2175) BN 5
J 2
(-2848 2183);
DISPLAY 0.617021 (-2848 2183);
PAINT GREEN (-2848 2183);
FORCEPROP 2 LAST CDS_LIB mstr_standard
J 0
(-2850 2175);
PAINT MONO (-2850 2175);
DISPLAY INVISIBLE (-2850 2175);
FORCEPROP 1 LAST BODY_TYPE PLUMBING
J 2
(-2850 2125);
DISPLAY 1.595745 (-2850 2125);
PAINT GREEN (-2850 2125);
DISPLAY INVISIBLE (-2850 2125);
FORCEPROP 1 LAST HDL_TAP TRUE
J 2
(-3175 2050);
DISPLAY 1.595745 (-3175 2050);
PAINT GREEN (-3175 2050);
DISPLAY INVISIBLE (-3175 2050);
FORCEPROP 1 LAST PATH I112
J 2
(-2848 2175);
DISPLAY 0.872340 (-2848 2175);
PAINT GREEN (-2848 2175);
DISPLAY INVISIBLE (-2848 2175);
FORCEADD TAP..6
R 2
(-2850 2225);
FORCEPROP 3 LASTPIN (-2900 2225) SIG_NAME M_L_MA<6>
J 0
(-2890 2235);
DISPLAY 0.659574 (-2890 2235);
PAINT MONO (-2890 2235);
DISPLAY INVISIBLE (-2890 2235);
FORCEPROP 1 LASTPIN (-2900 2225) BN 6
J 2
(-2848 2233);
DISPLAY 0.617021 (-2848 2233);
PAINT GREEN (-2848 2233);
FORCEPROP 2 LAST CDS_LIB mstr_standard
J 0
(-2850 2225);
PAINT MONO (-2850 2225);
DISPLAY INVISIBLE (-2850 2225);
FORCEPROP 1 LAST BODY_TYPE PLUMBING
J 2
(-2850 2175);
DISPLAY 1.595745 (-2850 2175);
PAINT GREEN (-2850 2175);
DISPLAY INVISIBLE (-2850 2175);
FORCEPROP 1 LAST HDL_TAP TRUE
J 2
(-3175 2100);
DISPLAY 1.595745 (-3175 2100);
PAINT GREEN (-3175 2100);
DISPLAY INVISIBLE (-3175 2100);
FORCEPROP 1 LAST PATH I113
J 2
(-2848 2225);
DISPLAY 0.872340 (-2848 2225);
PAINT GREEN (-2848 2225);
DISPLAY INVISIBLE (-2848 2225);
FORCEADD TAP..6
R 2
(-2850 2325);
FORCEPROP 3 LASTPIN (-2900 2325) SIG_NAME M_L_MA<8>
J 0
(-2890 2335);
DISPLAY 0.659574 (-2890 2335);
PAINT MONO (-2890 2335);
DISPLAY INVISIBLE (-2890 2335);
FORCEPROP 1 LASTPIN (-2900 2325) BN 8
J 2
(-2848 2333);
DISPLAY 0.617021 (-2848 2333);
PAINT GREEN (-2848 2333);
FORCEPROP 2 LAST CDS_LIB mstr_standard
J 0
(-2850 2325);
PAINT MONO (-2850 2325);
DISPLAY INVISIBLE (-2850 2325);
FORCEPROP 1 LAST BODY_TYPE PLUMBING
J 2
(-2850 2275);
DISPLAY 1.595745 (-2850 2275);
PAINT GREEN (-2850 2275);
DISPLAY INVISIBLE (-2850 2275);
FORCEPROP 1 LAST HDL_TAP TRUE
J 2
(-3175 2200);
DISPLAY 1.595745 (-3175 2200);
PAINT GREEN (-3175 2200);
DISPLAY INVISIBLE (-3175 2200);
FORCEPROP 1 LAST PATH I114
J 2
(-2848 2325);
DISPLAY 0.872340 (-2848 2325);
PAINT GREEN (-2848 2325);
DISPLAY INVISIBLE (-2848 2325);
FORCEADD TAP..6
R 2
(-2850 2275);
FORCEPROP 3 LASTPIN (-2900 2275) SIG_NAME M_L_MA<7>
J 0
(-2890 2285);
DISPLAY 0.659574 (-2890 2285);
PAINT MONO (-2890 2285);
DISPLAY INVISIBLE (-2890 2285);
FORCEPROP 1 LASTPIN (-2900 2275) BN 7
J 2
(-2848 2283);
DISPLAY 0.617021 (-2848 2283);
PAINT GREEN (-2848 2283);
FORCEPROP 2 LAST CDS_LIB mstr_standard
J 0
(-2850 2275);
PAINT MONO (-2850 2275);
DISPLAY INVISIBLE (-2850 2275);
FORCEPROP 1 LAST BODY_TYPE PLUMBING
J 2
(-2850 2225);
DISPLAY 1.595745 (-2850 2225);
PAINT GREEN (-2850 2225);
DISPLAY INVISIBLE (-2850 2225);
FORCEPROP 1 LAST HDL_TAP TRUE
J 2
(-3175 2150);
DISPLAY 1.595745 (-3175 2150);
PAINT GREEN (-3175 2150);
DISPLAY INVISIBLE (-3175 2150);
FORCEPROP 1 LAST PATH I115
J 2
(-2848 2275);
DISPLAY 0.872340 (-2848 2275);
PAINT GREEN (-2848 2275);
DISPLAY INVISIBLE (-2848 2275);
FORCEADD TAP..6
R 2
(-2850 2475);
FORCEPROP 3 LASTPIN (-2900 2475) SIG_NAME M_L_MA<11>
J 0
(-2890 2485);
DISPLAY 0.659574 (-2890 2485);
PAINT MONO (-2890 2485);
DISPLAY INVISIBLE (-2890 2485);
FORCEPROP 1 LASTPIN (-2900 2475) BN 11
J 2
(-2848 2483);
DISPLAY 0.617021 (-2848 2483);
PAINT GREEN (-2848 2483);
FORCEPROP 2 LAST CDS_LIB mstr_standard
J 0
(-2850 2475);
PAINT MONO (-2850 2475);
DISPLAY INVISIBLE (-2850 2475);
FORCEPROP 1 LAST BODY_TYPE PLUMBING
J 2
(-2850 2425);
DISPLAY 1.595745 (-2850 2425);
PAINT GREEN (-2850 2425);
DISPLAY INVISIBLE (-2850 2425);
FORCEPROP 1 LAST HDL_TAP TRUE
J 2
(-3175 2350);
DISPLAY 1.595745 (-3175 2350);
PAINT GREEN (-3175 2350);
DISPLAY INVISIBLE (-3175 2350);
FORCEPROP 1 LAST PATH I116
J 2
(-2848 2475);
DISPLAY 0.872340 (-2848 2475);
PAINT GREEN (-2848 2475);
DISPLAY INVISIBLE (-2848 2475);
FORCEADD TAP..6
R 2
(-2850 2425);
FORCEPROP 3 LASTPIN (-2900 2425) SIG_NAME M_L_MA<10>
J 0
(-2890 2435);
DISPLAY 0.659574 (-2890 2435);
PAINT MONO (-2890 2435);
DISPLAY INVISIBLE (-2890 2435);
FORCEPROP 1 LASTPIN (-2900 2425) BN 10
J 2
(-2848 2433);
DISPLAY 0.617021 (-2848 2433);
PAINT GREEN (-2848 2433);
FORCEPROP 2 LAST CDS_LIB mstr_standard
J 0
(-2850 2425);
PAINT MONO (-2850 2425);
DISPLAY INVISIBLE (-2850 2425);
FORCEPROP 1 LAST BODY_TYPE PLUMBING
J 2
(-2850 2375);
DISPLAY 1.595745 (-2850 2375);
PAINT GREEN (-2850 2375);
DISPLAY INVISIBLE (-2850 2375);
FORCEPROP 1 LAST HDL_TAP TRUE
J 2
(-3175 2300);
DISPLAY 1.595745 (-3175 2300);
PAINT GREEN (-3175 2300);
DISPLAY INVISIBLE (-3175 2300);
FORCEPROP 1 LAST PATH I117
J 2
(-2848 2425);
DISPLAY 0.872340 (-2848 2425);
PAINT GREEN (-2848 2425);
DISPLAY INVISIBLE (-2848 2425);
FORCEADD TAP..6
R 2
(-2850 2375);
FORCEPROP 3 LASTPIN (-2900 2375) SIG_NAME M_L_MA<9>
J 0
(-2890 2385);
DISPLAY 0.659574 (-2890 2385);
PAINT MONO (-2890 2385);
DISPLAY INVISIBLE (-2890 2385);
FORCEPROP 1 LASTPIN (-2900 2375) BN 9
J 2
(-2848 2383);
DISPLAY 0.617021 (-2848 2383);
PAINT GREEN (-2848 2383);
FORCEPROP 2 LAST CDS_LIB mstr_standard
J 0
(-2850 2375);
PAINT MONO (-2850 2375);
DISPLAY INVISIBLE (-2850 2375);
FORCEPROP 1 LAST BODY_TYPE PLUMBING
J 2
(-2850 2325);
DISPLAY 1.595745 (-2850 2325);
PAINT GREEN (-2850 2325);
DISPLAY INVISIBLE (-2850 2325);
FORCEPROP 1 LAST HDL_TAP TRUE
J 2
(-3175 2250);
DISPLAY 1.595745 (-3175 2250);
PAINT GREEN (-3175 2250);
DISPLAY INVISIBLE (-3175 2250);
FORCEPROP 1 LAST PATH I118
J 2
(-2848 2375);
DISPLAY 0.872340 (-2848 2375);
PAINT GREEN (-2848 2375);
DISPLAY INVISIBLE (-2848 2375);
FORCEADD TAP..6
R 2
(-2850 2525);
FORCEPROP 3 LASTPIN (-2900 2525) SIG_NAME M_L_MA<12>
J 0
(-2890 2535);
DISPLAY 0.659574 (-2890 2535);
PAINT MONO (-2890 2535);
DISPLAY INVISIBLE (-2890 2535);
FORCEPROP 1 LASTPIN (-2900 2525) BN 12
J 2
(-2848 2533);
DISPLAY 0.617021 (-2848 2533);
PAINT GREEN (-2848 2533);
FORCEPROP 2 LAST CDS_LIB mstr_standard
J 0
(-2850 2525);
PAINT MONO (-2850 2525);
DISPLAY INVISIBLE (-2850 2525);
FORCEPROP 1 LAST BODY_TYPE PLUMBING
J 2
(-2850 2475);
DISPLAY 1.595745 (-2850 2475);
PAINT GREEN (-2850 2475);
DISPLAY INVISIBLE (-2850 2475);
FORCEPROP 1 LAST HDL_TAP TRUE
J 2
(-3175 2400);
DISPLAY 1.595745 (-3175 2400);
PAINT GREEN (-3175 2400);
DISPLAY INVISIBLE (-3175 2400);
FORCEPROP 1 LAST PATH I119
J 2
(-2848 2525);
DISPLAY 0.872340 (-2848 2525);
PAINT GREEN (-2848 2525);
DISPLAY INVISIBLE (-2848 2525);
FORCEADD TAP..6
(-5575 975);
FORCEPROP 3 LASTPIN (-5525 975) SIG_NAME M_L_CLK_DP<3>
J 0
(-5515 985);
DISPLAY 0.659574 (-5515 985);
PAINT MONO (-5515 985);
DISPLAY INVISIBLE (-5515 985);
FORCEPROP 1 LASTPIN (-5525 975) BN 3
J 0
(-5577 983);
DISPLAY 0.617021 (-5577 983);
PAINT GREEN (-5577 983);
FORCEPROP 2 LAST CDS_LIB mstr_standard
J 0
(-5575 975);
PAINT MONO (-5575 975);
DISPLAY INVISIBLE (-5575 975);
FORCEPROP 1 LAST BODY_TYPE PLUMBING
J 0
(-5575 925);
DISPLAY 1.595745 (-5575 925);
PAINT GREEN (-5575 925);
DISPLAY INVISIBLE (-5575 925);
FORCEPROP 1 LAST HDL_TAP TRUE
J 0
(-5250 850);
DISPLAY 1.595745 (-5250 850);
PAINT GREEN (-5250 850);
DISPLAY INVISIBLE (-5250 850);
FORCEPROP 1 LAST PATH I12
J 0
(-5577 975);
DISPLAY 0.872340 (-5577 975);
PAINT GREEN (-5577 975);
DISPLAY INVISIBLE (-5577 975);
FORCEADD TAP..6
R 2
(-2850 2575);
FORCEPROP 3 LASTPIN (-2900 2575) SIG_NAME M_L_MA<13>
J 0
(-2890 2585);
DISPLAY 0.659574 (-2890 2585);
PAINT MONO (-2890 2585);
DISPLAY INVISIBLE (-2890 2585);
FORCEPROP 1 LASTPIN (-2900 2575) BN 13
J 2
(-2848 2583);
DISPLAY 0.617021 (-2848 2583);
PAINT GREEN (-2848 2583);
FORCEPROP 2 LAST CDS_LIB mstr_standard
J 0
(-2850 2575);
PAINT MONO (-2850 2575);
DISPLAY INVISIBLE (-2850 2575);
FORCEPROP 1 LAST BODY_TYPE PLUMBING
J 2
(-2850 2525);
DISPLAY 1.595745 (-2850 2525);
PAINT GREEN (-2850 2525);
DISPLAY INVISIBLE (-2850 2525);
FORCEPROP 1 LAST HDL_TAP TRUE
J 2
(-3175 2450);
DISPLAY 1.595745 (-3175 2450);
PAINT GREEN (-3175 2450);
DISPLAY INVISIBLE (-3175 2450);
FORCEPROP 1 LAST PATH I120
J 2
(-2848 2575);
DISPLAY 0.872340 (-2848 2575);
PAINT GREEN (-2848 2575);
DISPLAY INVISIBLE (-2848 2575);
FORCEADD TAP..6
R 2
(-2850 2625);
FORCEPROP 3 LASTPIN (-2900 2625) SIG_NAME M_L_MA<14>
J 0
(-2890 2635);
DISPLAY 0.659574 (-2890 2635);
PAINT MONO (-2890 2635);
DISPLAY INVISIBLE (-2890 2635);
FORCEPROP 1 LASTPIN (-2900 2625) BN 14
J 2
(-2848 2633);
DISPLAY 0.617021 (-2848 2633);
PAINT GREEN (-2848 2633);
FORCEPROP 2 LAST CDS_LIB mstr_standard
J 0
(-2850 2625);
PAINT MONO (-2850 2625);
DISPLAY INVISIBLE (-2850 2625);
FORCEPROP 1 LAST BODY_TYPE PLUMBING
J 2
(-2850 2575);
DISPLAY 1.595745 (-2850 2575);
PAINT GREEN (-2850 2575);
DISPLAY INVISIBLE (-2850 2575);
FORCEPROP 1 LAST HDL_TAP TRUE
J 2
(-3175 2500);
DISPLAY 1.595745 (-3175 2500);
PAINT GREEN (-3175 2500);
DISPLAY INVISIBLE (-3175 2500);
FORCEPROP 1 LAST PATH I121
J 2
(-2848 2625);
DISPLAY 0.872340 (-2848 2625);
PAINT GREEN (-2848 2625);
DISPLAY INVISIBLE (-2848 2625);
FORCEADD TAP..6
R 2
(-2850 2675);
FORCEPROP 3 LASTPIN (-2900 2675) SIG_NAME M_L_MA<15>
J 0
(-2890 2685);
DISPLAY 0.659574 (-2890 2685);
PAINT MONO (-2890 2685);
DISPLAY INVISIBLE (-2890 2685);
FORCEPROP 1 LASTPIN (-2900 2675) BN 15
J 2
(-2848 2683);
DISPLAY 0.617021 (-2848 2683);
PAINT GREEN (-2848 2683);
FORCEPROP 2 LAST CDS_LIB mstr_standard
J 0
(-2850 2675);
PAINT MONO (-2850 2675);
DISPLAY INVISIBLE (-2850 2675);
FORCEPROP 1 LAST BODY_TYPE PLUMBING
J 2
(-2850 2625);
DISPLAY 1.595745 (-2850 2625);
PAINT GREEN (-2850 2625);
DISPLAY INVISIBLE (-2850 2625);
FORCEPROP 1 LAST HDL_TAP TRUE
J 2
(-3175 2550);
DISPLAY 1.595745 (-3175 2550);
PAINT GREEN (-3175 2550);
DISPLAY INVISIBLE (-3175 2550);
FORCEPROP 1 LAST PATH I122
J 2
(-2848 2675);
DISPLAY 0.872340 (-2848 2675);
PAINT GREEN (-2848 2675);
DISPLAY INVISIBLE (-2848 2675);
FORCEADD TAP..6
R 2
(-2850 2725);
FORCEPROP 3 LASTPIN (-2900 2725) SIG_NAME M_L_MA<16>
J 0
(-2890 2735);
DISPLAY 0.659574 (-2890 2735);
PAINT MONO (-2890 2735);
DISPLAY INVISIBLE (-2890 2735);
FORCEPROP 1 LASTPIN (-2900 2725) BN 16
J 2
(-2848 2733);
DISPLAY 0.617021 (-2848 2733);
PAINT GREEN (-2848 2733);
FORCEPROP 2 LAST CDS_LIB mstr_standard
J 0
(-2850 2725);
PAINT MONO (-2850 2725);
DISPLAY INVISIBLE (-2850 2725);
FORCEPROP 1 LAST BODY_TYPE PLUMBING
J 2
(-2850 2675);
DISPLAY 1.595745 (-2850 2675);
PAINT GREEN (-2850 2675);
DISPLAY INVISIBLE (-2850 2675);
FORCEPROP 1 LAST HDL_TAP TRUE
J 2
(-3175 2600);
DISPLAY 1.595745 (-3175 2600);
PAINT GREEN (-3175 2600);
DISPLAY INVISIBLE (-3175 2600);
FORCEPROP 1 LAST PATH I123
J 2
(-2848 2725);
DISPLAY 0.872340 (-2848 2725);
PAINT GREEN (-2848 2725);
DISPLAY INVISIBLE (-2848 2725);
FORCEADD TAP..6
R 2
(-2850 2775);
FORCEPROP 3 LASTPIN (-2900 2775) SIG_NAME M_L_MA<17>
J 0
(-2890 2785);
DISPLAY 0.659574 (-2890 2785);
PAINT MONO (-2890 2785);
DISPLAY INVISIBLE (-2890 2785);
FORCEPROP 1 LASTPIN (-2900 2775) BN 17
J 2
(-2848 2783);
DISPLAY 0.617021 (-2848 2783);
PAINT GREEN (-2848 2783);
FORCEPROP 2 LAST CDS_LIB mstr_standard
J 0
(-2850 2775);
PAINT MONO (-2850 2775);
DISPLAY INVISIBLE (-2850 2775);
FORCEPROP 1 LAST BODY_TYPE PLUMBING
J 2
(-2850 2725);
DISPLAY 1.595745 (-2850 2725);
PAINT GREEN (-2850 2725);
DISPLAY INVISIBLE (-2850 2725);
FORCEPROP 1 LAST HDL_TAP TRUE
J 2
(-3175 2650);
DISPLAY 1.595745 (-3175 2650);
PAINT GREEN (-3175 2650);
DISPLAY INVISIBLE (-3175 2650);
FORCEPROP 1 LAST PATH I124
J 2
(-2848 2775);
DISPLAY 0.872340 (-2848 2775);
PAINT GREEN (-2848 2775);
DISPLAY INVISIBLE (-2848 2775);
FORCEADD TAP..6
R 2
(-2850 2925);
FORCEPROP 3 LASTPIN (-2900 2925) SIG_NAME M_L_DQS_DN<1>
J 0
(-2890 2935);
DISPLAY 0.659574 (-2890 2935);
PAINT MONO (-2890 2935);
DISPLAY INVISIBLE (-2890 2935);
FORCEPROP 1 LASTPIN (-2900 2925) BN 1
J 2
(-2848 2933);
DISPLAY 0.617021 (-2848 2933);
PAINT GREEN (-2848 2933);
FORCEPROP 2 LAST CDS_LIB mstr_standard
J 0
(-2850 2925);
PAINT MONO (-2850 2925);
DISPLAY INVISIBLE (-2850 2925);
FORCEPROP 1 LAST BODY_TYPE PLUMBING
J 2
(-2850 2875);
DISPLAY 1.595745 (-2850 2875);
PAINT GREEN (-2850 2875);
DISPLAY INVISIBLE (-2850 2875);
FORCEPROP 1 LAST HDL_TAP TRUE
J 2
(-3175 2800);
DISPLAY 1.595745 (-3175 2800);
PAINT GREEN (-3175 2800);
DISPLAY INVISIBLE (-3175 2800);
FORCEPROP 1 LAST PATH I125
J 2
(-2848 2925);
DISPLAY 0.872340 (-2848 2925);
PAINT GREEN (-2848 2925);
DISPLAY INVISIBLE (-2848 2925);
FORCEADD TAP..6
R 2
(-2850 2975);
FORCEPROP 3 LASTPIN (-2900 2975) SIG_NAME M_L_DQS_DN<2>
J 0
(-2890 2985);
DISPLAY 0.659574 (-2890 2985);
PAINT MONO (-2890 2985);
DISPLAY INVISIBLE (-2890 2985);
FORCEPROP 1 LASTPIN (-2900 2975) BN 2
J 2
(-2848 2983);
DISPLAY 0.617021 (-2848 2983);
PAINT GREEN (-2848 2983);
FORCEPROP 2 LAST CDS_LIB mstr_standard
J 0
(-2850 2975);
PAINT MONO (-2850 2975);
DISPLAY INVISIBLE (-2850 2975);
FORCEPROP 1 LAST BODY_TYPE PLUMBING
J 2
(-2850 2925);
DISPLAY 1.595745 (-2850 2925);
PAINT GREEN (-2850 2925);
DISPLAY INVISIBLE (-2850 2925);
FORCEPROP 1 LAST HDL_TAP TRUE
J 2
(-3175 2850);
DISPLAY 1.595745 (-3175 2850);
PAINT GREEN (-3175 2850);
DISPLAY INVISIBLE (-3175 2850);
FORCEPROP 1 LAST PATH I126
J 2
(-2848 2975);
DISPLAY 0.872340 (-2848 2975);
PAINT GREEN (-2848 2975);
DISPLAY INVISIBLE (-2848 2975);
FORCEADD TAP..6
R 2
(-2850 2875);
FORCEPROP 3 LASTPIN (-2900 2875) SIG_NAME M_L_DQS_DN<0>
J 0
(-2890 2885);
DISPLAY 0.659574 (-2890 2885);
PAINT MONO (-2890 2885);
DISPLAY INVISIBLE (-2890 2885);
FORCEPROP 1 LASTPIN (-2900 2875) BN 0
J 2
(-2848 2883);
DISPLAY 0.617021 (-2848 2883);
PAINT GREEN (-2848 2883);
FORCEPROP 2 LAST CDS_LIB mstr_standard
J 0
(-2850 2875);
PAINT MONO (-2850 2875);
DISPLAY INVISIBLE (-2850 2875);
FORCEPROP 1 LAST BODY_TYPE PLUMBING
J 2
(-2850 2825);
DISPLAY 1.595745 (-2850 2825);
PAINT GREEN (-2850 2825);
DISPLAY INVISIBLE (-2850 2825);
FORCEPROP 1 LAST HDL_TAP TRUE
J 2
(-3175 2750);
DISPLAY 1.595745 (-3175 2750);
PAINT GREEN (-3175 2750);
DISPLAY INVISIBLE (-3175 2750);
FORCEPROP 1 LAST PATH I127
J 2
(-2848 2875);
DISPLAY 0.872340 (-2848 2875);
PAINT GREEN (-2848 2875);
DISPLAY INVISIBLE (-2848 2875);
FORCEADD TAP..6
R 2
(-2850 3075);
FORCEPROP 3 LASTPIN (-2900 3075) SIG_NAME M_L_DQS_DN<4>
J 0
(-2890 3085);
DISPLAY 0.659574 (-2890 3085);
PAINT MONO (-2890 3085);
DISPLAY INVISIBLE (-2890 3085);
FORCEPROP 1 LASTPIN (-2900 3075) BN 4
J 2
(-2848 3083);
DISPLAY 0.617021 (-2848 3083);
PAINT GREEN (-2848 3083);
FORCEPROP 2 LAST CDS_LIB mstr_standard
J 0
(-2850 3075);
PAINT MONO (-2850 3075);
DISPLAY INVISIBLE (-2850 3075);
FORCEPROP 1 LAST BODY_TYPE PLUMBING
J 2
(-2850 3025);
DISPLAY 1.595745 (-2850 3025);
PAINT GREEN (-2850 3025);
DISPLAY INVISIBLE (-2850 3025);
FORCEPROP 1 LAST HDL_TAP TRUE
J 2
(-3175 2950);
DISPLAY 1.595745 (-3175 2950);
PAINT GREEN (-3175 2950);
DISPLAY INVISIBLE (-3175 2950);
FORCEPROP 1 LAST PATH I128
J 2
(-2848 3075);
DISPLAY 0.872340 (-2848 3075);
PAINT GREEN (-2848 3075);
DISPLAY INVISIBLE (-2848 3075);
FORCEADD TAP..6
R 2
(-2850 3025);
FORCEPROP 3 LASTPIN (-2900 3025) SIG_NAME M_L_DQS_DN<3>
J 0
(-2890 3035);
DISPLAY 0.659574 (-2890 3035);
PAINT MONO (-2890 3035);
DISPLAY INVISIBLE (-2890 3035);
FORCEPROP 1 LASTPIN (-2900 3025) BN 3
J 2
(-2848 3033);
DISPLAY 0.617021 (-2848 3033);
PAINT GREEN (-2848 3033);
FORCEPROP 2 LAST CDS_LIB mstr_standard
J 0
(-2850 3025);
PAINT MONO (-2850 3025);
DISPLAY INVISIBLE (-2850 3025);
FORCEPROP 1 LAST BODY_TYPE PLUMBING
J 2
(-2850 2975);
DISPLAY 1.595745 (-2850 2975);
PAINT GREEN (-2850 2975);
DISPLAY INVISIBLE (-2850 2975);
FORCEPROP 1 LAST HDL_TAP TRUE
J 2
(-3175 2900);
DISPLAY 1.595745 (-3175 2900);
PAINT GREEN (-3175 2900);
DISPLAY INVISIBLE (-3175 2900);
FORCEPROP 1 LAST PATH I129
J 2
(-2848 3025);
DISPLAY 0.872340 (-2848 3025);
PAINT GREEN (-2848 3025);
DISPLAY INVISIBLE (-2848 3025);
FORCEADD TAP..6
(-5575 1075);
FORCEPROP 3 LASTPIN (-5525 1075) SIG_NAME M_L_ECC<0>
J 0
(-5515 1085);
DISPLAY 0.659574 (-5515 1085);
PAINT MONO (-5515 1085);
DISPLAY INVISIBLE (-5515 1085);
FORCEPROP 1 LASTPIN (-5525 1075) BN 0
J 0
(-5577 1083);
DISPLAY 0.617021 (-5577 1083);
PAINT GREEN (-5577 1083);
FORCEPROP 2 LAST CDS_LIB mstr_standard
J 0
(-5575 1075);
PAINT MONO (-5575 1075);
DISPLAY INVISIBLE (-5575 1075);
FORCEPROP 1 LAST BODY_TYPE PLUMBING
J 0
(-5575 1025);
DISPLAY 1.595745 (-5575 1025);
PAINT GREEN (-5575 1025);
DISPLAY INVISIBLE (-5575 1025);
FORCEPROP 1 LAST HDL_TAP TRUE
J 0
(-5250 950);
DISPLAY 1.595745 (-5250 950);
PAINT GREEN (-5250 950);
DISPLAY INVISIBLE (-5250 950);
FORCEPROP 1 LAST PATH I13
J 0
(-5577 1075);
DISPLAY 0.872340 (-5577 1075);
PAINT GREEN (-5577 1075);
DISPLAY INVISIBLE (-5577 1075);
FORCEADD TAP..6
R 2
(-2850 3125);
FORCEPROP 3 LASTPIN (-2900 3125) SIG_NAME M_L_DQS_DN<5>
J 0
(-2890 3135);
DISPLAY 0.659574 (-2890 3135);
PAINT MONO (-2890 3135);
DISPLAY INVISIBLE (-2890 3135);
FORCEPROP 1 LASTPIN (-2900 3125) BN 5
J 2
(-2848 3133);
DISPLAY 0.617021 (-2848 3133);
PAINT GREEN (-2848 3133);
FORCEPROP 2 LAST CDS_LIB mstr_standard
J 0
(-2850 3125);
PAINT MONO (-2850 3125);
DISPLAY INVISIBLE (-2850 3125);
FORCEPROP 1 LAST BODY_TYPE PLUMBING
J 2
(-2850 3075);
DISPLAY 1.595745 (-2850 3075);
PAINT GREEN (-2850 3075);
DISPLAY INVISIBLE (-2850 3075);
FORCEPROP 1 LAST HDL_TAP TRUE
J 2
(-3175 3000);
DISPLAY 1.595745 (-3175 3000);
PAINT GREEN (-3175 3000);
DISPLAY INVISIBLE (-3175 3000);
FORCEPROP 1 LAST PATH I130
J 2
(-2848 3125);
DISPLAY 0.872340 (-2848 3125);
PAINT GREEN (-2848 3125);
DISPLAY INVISIBLE (-2848 3125);
FORCEADD TAP..6
R 2
(-2850 3175);
FORCEPROP 3 LASTPIN (-2900 3175) SIG_NAME M_L_DQS_DN<6>
J 0
(-2890 3185);
DISPLAY 0.659574 (-2890 3185);
PAINT MONO (-2890 3185);
DISPLAY INVISIBLE (-2890 3185);
FORCEPROP 1 LASTPIN (-2900 3175) BN 6
J 2
(-2848 3183);
DISPLAY 0.617021 (-2848 3183);
PAINT GREEN (-2848 3183);
FORCEPROP 2 LAST CDS_LIB mstr_standard
J 0
(-2850 3175);
PAINT MONO (-2850 3175);
DISPLAY INVISIBLE (-2850 3175);
FORCEPROP 1 LAST BODY_TYPE PLUMBING
J 2
(-2850 3125);
DISPLAY 1.595745 (-2850 3125);
PAINT GREEN (-2850 3125);
DISPLAY INVISIBLE (-2850 3125);
FORCEPROP 1 LAST HDL_TAP TRUE
J 2
(-3175 3050);
DISPLAY 1.595745 (-3175 3050);
PAINT GREEN (-3175 3050);
DISPLAY INVISIBLE (-3175 3050);
FORCEPROP 1 LAST PATH I131
J 2
(-2848 3175);
DISPLAY 0.872340 (-2848 3175);
PAINT GREEN (-2848 3175);
DISPLAY INVISIBLE (-2848 3175);
FORCEADD TAP..6
R 2
(-2850 3225);
FORCEPROP 3 LASTPIN (-2900 3225) SIG_NAME M_L_DQS_DN<7>
J 0
(-2890 3235);
DISPLAY 0.659574 (-2890 3235);
PAINT MONO (-2890 3235);
DISPLAY INVISIBLE (-2890 3235);
FORCEPROP 1 LASTPIN (-2900 3225) BN 7
J 2
(-2848 3233);
DISPLAY 0.617021 (-2848 3233);
PAINT GREEN (-2848 3233);
FORCEPROP 2 LAST CDS_LIB mstr_standard
J 0
(-2850 3225);
PAINT MONO (-2850 3225);
DISPLAY INVISIBLE (-2850 3225);
FORCEPROP 1 LAST BODY_TYPE PLUMBING
J 2
(-2850 3175);
DISPLAY 1.595745 (-2850 3175);
PAINT GREEN (-2850 3175);
DISPLAY INVISIBLE (-2850 3175);
FORCEPROP 1 LAST HDL_TAP TRUE
J 2
(-3175 3100);
DISPLAY 1.595745 (-3175 3100);
PAINT GREEN (-3175 3100);
DISPLAY INVISIBLE (-3175 3100);
FORCEPROP 1 LAST PATH I132
J 2
(-2848 3225);
DISPLAY 0.872340 (-2848 3225);
PAINT GREEN (-2848 3225);
DISPLAY INVISIBLE (-2848 3225);
FORCEADD TAP..6
R 2
(-2850 3275);
FORCEPROP 3 LASTPIN (-2900 3275) SIG_NAME M_L_DQS_DN<8>
J 0
(-2890 3285);
DISPLAY 0.659574 (-2890 3285);
PAINT MONO (-2890 3285);
DISPLAY INVISIBLE (-2890 3285);
FORCEPROP 1 LASTPIN (-2900 3275) BN 8
J 2
(-2848 3283);
DISPLAY 0.617021 (-2848 3283);
PAINT GREEN (-2848 3283);
FORCEPROP 2 LAST CDS_LIB mstr_standard
J 0
(-2850 3275);
PAINT MONO (-2850 3275);
DISPLAY INVISIBLE (-2850 3275);
FORCEPROP 1 LAST BODY_TYPE PLUMBING
J 2
(-2850 3225);
DISPLAY 1.595745 (-2850 3225);
PAINT GREEN (-2850 3225);
DISPLAY INVISIBLE (-2850 3225);
FORCEPROP 1 LAST HDL_TAP TRUE
J 2
(-3175 3150);
DISPLAY 1.595745 (-3175 3150);
PAINT GREEN (-3175 3150);
DISPLAY INVISIBLE (-3175 3150);
FORCEPROP 1 LAST PATH I133
J 2
(-2848 3275);
DISPLAY 0.872340 (-2848 3275);
PAINT GREEN (-2848 3275);
DISPLAY INVISIBLE (-2848 3275);
FORCEADD TAP..6
R 2
(-2850 3325);
FORCEPROP 3 LASTPIN (-2900 3325) SIG_NAME M_L_DQS_DN<9>
J 0
(-2890 3335);
DISPLAY 0.659574 (-2890 3335);
PAINT MONO (-2890 3335);
DISPLAY INVISIBLE (-2890 3335);
FORCEPROP 1 LASTPIN (-2900 3325) BN 9
J 2
(-2848 3333);
DISPLAY 0.617021 (-2848 3333);
PAINT GREEN (-2848 3333);
FORCEPROP 2 LAST CDS_LIB mstr_standard
J 0
(-2850 3325);
PAINT MONO (-2850 3325);
DISPLAY INVISIBLE (-2850 3325);
FORCEPROP 1 LAST BODY_TYPE PLUMBING
J 2
(-2850 3275);
DISPLAY 1.595745 (-2850 3275);
PAINT GREEN (-2850 3275);
DISPLAY INVISIBLE (-2850 3275);
FORCEPROP 1 LAST HDL_TAP TRUE
J 2
(-3175 3200);
DISPLAY 1.595745 (-3175 3200);
PAINT GREEN (-3175 3200);
DISPLAY INVISIBLE (-3175 3200);
FORCEPROP 1 LAST PATH I134
J 2
(-2848 3325);
DISPLAY 0.872340 (-2848 3325);
PAINT GREEN (-2848 3325);
DISPLAY INVISIBLE (-2848 3325);
FORCEADD TAP..6
R 2
(-2850 3375);
FORCEPROP 3 LASTPIN (-2900 3375) SIG_NAME M_L_DQS_DN<10>
J 0
(-2890 3385);
DISPLAY 0.659574 (-2890 3385);
PAINT MONO (-2890 3385);
DISPLAY INVISIBLE (-2890 3385);
FORCEPROP 1 LASTPIN (-2900 3375) BN 10
J 2
(-2848 3383);
DISPLAY 0.617021 (-2848 3383);
PAINT GREEN (-2848 3383);
FORCEPROP 2 LAST CDS_LIB mstr_standard
J 0
(-2850 3375);
PAINT MONO (-2850 3375);
DISPLAY INVISIBLE (-2850 3375);
FORCEPROP 1 LAST BODY_TYPE PLUMBING
J 2
(-2850 3325);
DISPLAY 1.595745 (-2850 3325);
PAINT GREEN (-2850 3325);
DISPLAY INVISIBLE (-2850 3325);
FORCEPROP 1 LAST HDL_TAP TRUE
J 2
(-3175 3250);
DISPLAY 1.595745 (-3175 3250);
PAINT GREEN (-3175 3250);
DISPLAY INVISIBLE (-3175 3250);
FORCEPROP 1 LAST PATH I135
J 2
(-2848 3375);
DISPLAY 0.872340 (-2848 3375);
PAINT GREEN (-2848 3375);
DISPLAY INVISIBLE (-2848 3375);
FORCEADD TAP..6
R 2
(-2850 3475);
FORCEPROP 3 LASTPIN (-2900 3475) SIG_NAME M_L_DQS_DN<12>
J 0
(-2890 3485);
DISPLAY 0.659574 (-2890 3485);
PAINT MONO (-2890 3485);
DISPLAY INVISIBLE (-2890 3485);
FORCEPROP 1 LASTPIN (-2900 3475) BN 12
J 2
(-2848 3483);
DISPLAY 0.617021 (-2848 3483);
PAINT GREEN (-2848 3483);
FORCEPROP 2 LAST CDS_LIB mstr_standard
J 0
(-2850 3475);
PAINT MONO (-2850 3475);
DISPLAY INVISIBLE (-2850 3475);
FORCEPROP 1 LAST BODY_TYPE PLUMBING
J 2
(-2850 3425);
DISPLAY 1.595745 (-2850 3425);
PAINT GREEN (-2850 3425);
DISPLAY INVISIBLE (-2850 3425);
FORCEPROP 1 LAST HDL_TAP TRUE
J 2
(-3175 3350);
DISPLAY 1.595745 (-3175 3350);
PAINT GREEN (-3175 3350);
DISPLAY INVISIBLE (-3175 3350);
FORCEPROP 1 LAST PATH I136
J 2
(-2848 3475);
DISPLAY 0.872340 (-2848 3475);
PAINT GREEN (-2848 3475);
DISPLAY INVISIBLE (-2848 3475);
FORCEADD TAP..6
R 2
(-2850 3425);
FORCEPROP 3 LASTPIN (-2900 3425) SIG_NAME M_L_DQS_DN<11>
J 0
(-2890 3435);
DISPLAY 0.659574 (-2890 3435);
PAINT MONO (-2890 3435);
DISPLAY INVISIBLE (-2890 3435);
FORCEPROP 1 LASTPIN (-2900 3425) BN 11
J 2
(-2848 3433);
DISPLAY 0.617021 (-2848 3433);
PAINT GREEN (-2848 3433);
FORCEPROP 2 LAST CDS_LIB mstr_standard
J 0
(-2850 3425);
PAINT MONO (-2850 3425);
DISPLAY INVISIBLE (-2850 3425);
FORCEPROP 1 LAST BODY_TYPE PLUMBING
J 2
(-2850 3375);
DISPLAY 1.595745 (-2850 3375);
PAINT GREEN (-2850 3375);
DISPLAY INVISIBLE (-2850 3375);
FORCEPROP 1 LAST HDL_TAP TRUE
J 2
(-3175 3300);
DISPLAY 1.595745 (-3175 3300);
PAINT GREEN (-3175 3300);
DISPLAY INVISIBLE (-3175 3300);
FORCEPROP 1 LAST PATH I137
J 2
(-2848 3425);
DISPLAY 0.872340 (-2848 3425);
PAINT GREEN (-2848 3425);
DISPLAY INVISIBLE (-2848 3425);
FORCEADD TAP..6
R 2
(-2850 3625);
FORCEPROP 3 LASTPIN (-2900 3625) SIG_NAME M_L_DQS_DN<15>
J 0
(-2890 3635);
DISPLAY 0.659574 (-2890 3635);
PAINT MONO (-2890 3635);
DISPLAY INVISIBLE (-2890 3635);
FORCEPROP 1 LASTPIN (-2900 3625) BN 15
J 2
(-2848 3633);
DISPLAY 0.617021 (-2848 3633);
PAINT GREEN (-2848 3633);
FORCEPROP 2 LAST CDS_LIB mstr_standard
J 0
(-2850 3625);
PAINT MONO (-2850 3625);
DISPLAY INVISIBLE (-2850 3625);
FORCEPROP 1 LAST BODY_TYPE PLUMBING
J 2
(-2850 3575);
DISPLAY 1.595745 (-2850 3575);
PAINT GREEN (-2850 3575);
DISPLAY INVISIBLE (-2850 3575);
FORCEPROP 1 LAST HDL_TAP TRUE
J 2
(-3175 3500);
DISPLAY 1.595745 (-3175 3500);
PAINT GREEN (-3175 3500);
DISPLAY INVISIBLE (-3175 3500);
FORCEPROP 1 LAST PATH I138
J 2
(-2848 3625);
DISPLAY 0.872340 (-2848 3625);
PAINT GREEN (-2848 3625);
DISPLAY INVISIBLE (-2848 3625);
FORCEADD TAP..6
R 2
(-2850 3575);
FORCEPROP 3 LASTPIN (-2900 3575) SIG_NAME M_L_DQS_DN<14>
J 0
(-2890 3585);
DISPLAY 0.659574 (-2890 3585);
PAINT MONO (-2890 3585);
DISPLAY INVISIBLE (-2890 3585);
FORCEPROP 1 LASTPIN (-2900 3575) BN 14
J 2
(-2848 3583);
DISPLAY 0.617021 (-2848 3583);
PAINT GREEN (-2848 3583);
FORCEPROP 2 LAST CDS_LIB mstr_standard
J 0
(-2850 3575);
PAINT MONO (-2850 3575);
DISPLAY INVISIBLE (-2850 3575);
FORCEPROP 1 LAST BODY_TYPE PLUMBING
J 2
(-2850 3525);
DISPLAY 1.595745 (-2850 3525);
PAINT GREEN (-2850 3525);
DISPLAY INVISIBLE (-2850 3525);
FORCEPROP 1 LAST HDL_TAP TRUE
J 2
(-3175 3450);
DISPLAY 1.595745 (-3175 3450);
PAINT GREEN (-3175 3450);
DISPLAY INVISIBLE (-3175 3450);
FORCEPROP 1 LAST PATH I139
J 2
(-2848 3575);
DISPLAY 0.872340 (-2848 3575);
PAINT GREEN (-2848 3575);
DISPLAY INVISIBLE (-2848 3575);
FORCEADD TAP..6
(-5575 1125);
FORCEPROP 3 LASTPIN (-5525 1125) SIG_NAME M_L_ECC<1>
J 0
(-5515 1135);
DISPLAY 0.659574 (-5515 1135);
PAINT MONO (-5515 1135);
DISPLAY INVISIBLE (-5515 1135);
FORCEPROP 1 LASTPIN (-5525 1125) BN 1
J 0
(-5577 1133);
DISPLAY 0.617021 (-5577 1133);
PAINT GREEN (-5577 1133);
FORCEPROP 2 LAST CDS_LIB mstr_standard
J 0
(-5575 1125);
PAINT MONO (-5575 1125);
DISPLAY INVISIBLE (-5575 1125);
FORCEPROP 1 LAST BODY_TYPE PLUMBING
J 0
(-5575 1075);
DISPLAY 1.595745 (-5575 1075);
PAINT GREEN (-5575 1075);
DISPLAY INVISIBLE (-5575 1075);
FORCEPROP 1 LAST HDL_TAP TRUE
J 0
(-5250 1000);
DISPLAY 1.595745 (-5250 1000);
PAINT GREEN (-5250 1000);
DISPLAY INVISIBLE (-5250 1000);
FORCEPROP 1 LAST PATH I14
J 0
(-5577 1125);
DISPLAY 0.872340 (-5577 1125);
PAINT GREEN (-5577 1125);
DISPLAY INVISIBLE (-5577 1125);
FORCEADD TAP..6
R 2
(-2850 3525);
FORCEPROP 3 LASTPIN (-2900 3525) SIG_NAME M_L_DQS_DN<13>
J 0
(-2890 3535);
DISPLAY 0.659574 (-2890 3535);
PAINT MONO (-2890 3535);
DISPLAY INVISIBLE (-2890 3535);
FORCEPROP 1 LASTPIN (-2900 3525) BN 13
J 2
(-2848 3533);
DISPLAY 0.617021 (-2848 3533);
PAINT GREEN (-2848 3533);
FORCEPROP 2 LAST CDS_LIB mstr_standard
J 0
(-2850 3525);
PAINT MONO (-2850 3525);
DISPLAY INVISIBLE (-2850 3525);
FORCEPROP 1 LAST BODY_TYPE PLUMBING
J 2
(-2850 3475);
DISPLAY 1.595745 (-2850 3475);
PAINT GREEN (-2850 3475);
DISPLAY INVISIBLE (-2850 3475);
FORCEPROP 1 LAST HDL_TAP TRUE
J 2
(-3175 3400);
DISPLAY 1.595745 (-3175 3400);
PAINT GREEN (-3175 3400);
DISPLAY INVISIBLE (-3175 3400);
FORCEPROP 1 LAST PATH I140
J 2
(-2848 3525);
DISPLAY 0.872340 (-2848 3525);
PAINT GREEN (-2848 3525);
DISPLAY INVISIBLE (-2848 3525);
FORCEADD TAP..6
R 2
(-2850 3675);
FORCEPROP 3 LASTPIN (-2900 3675) SIG_NAME M_L_DQS_DN<16>
J 0
(-2890 3685);
DISPLAY 0.659574 (-2890 3685);
PAINT MONO (-2890 3685);
DISPLAY INVISIBLE (-2890 3685);
FORCEPROP 1 LASTPIN (-2900 3675) BN 16
J 2
(-2848 3683);
DISPLAY 0.617021 (-2848 3683);
PAINT GREEN (-2848 3683);
FORCEPROP 2 LAST CDS_LIB mstr_standard
J 0
(-2850 3675);
PAINT MONO (-2850 3675);
DISPLAY INVISIBLE (-2850 3675);
FORCEPROP 1 LAST BODY_TYPE PLUMBING
J 2
(-2850 3625);
DISPLAY 1.595745 (-2850 3625);
PAINT GREEN (-2850 3625);
DISPLAY INVISIBLE (-2850 3625);
FORCEPROP 1 LAST HDL_TAP TRUE
J 2
(-3175 3550);
DISPLAY 1.595745 (-3175 3550);
PAINT GREEN (-3175 3550);
DISPLAY INVISIBLE (-3175 3550);
FORCEPROP 1 LAST PATH I141
J 2
(-2848 3675);
DISPLAY 0.872340 (-2848 3675);
PAINT GREEN (-2848 3675);
DISPLAY INVISIBLE (-2848 3675);
FORCEADD TAP..6
R 2
(-2850 3725);
FORCEPROP 3 LASTPIN (-2900 3725) SIG_NAME M_L_DQS_DN<17>
J 0
(-2890 3735);
DISPLAY 0.659574 (-2890 3735);
PAINT MONO (-2890 3735);
DISPLAY INVISIBLE (-2890 3735);
FORCEPROP 1 LASTPIN (-2900 3725) BN 17
J 2
(-2848 3733);
DISPLAY 0.617021 (-2848 3733);
PAINT GREEN (-2848 3733);
FORCEPROP 2 LAST CDS_LIB mstr_standard
J 0
(-2850 3725);
PAINT MONO (-2850 3725);
DISPLAY INVISIBLE (-2850 3725);
FORCEPROP 1 LAST BODY_TYPE PLUMBING
J 2
(-2850 3675);
DISPLAY 1.595745 (-2850 3675);
PAINT GREEN (-2850 3675);
DISPLAY INVISIBLE (-2850 3675);
FORCEPROP 1 LAST HDL_TAP TRUE
J 2
(-3175 3600);
DISPLAY 1.595745 (-3175 3600);
PAINT GREEN (-3175 3600);
DISPLAY INVISIBLE (-3175 3600);
FORCEPROP 1 LAST PATH I142
J 2
(-2848 3725);
DISPLAY 0.872340 (-2848 3725);
PAINT GREEN (-2848 3725);
DISPLAY INVISIBLE (-2848 3725);
FORCEADD TAP..6
R 2
(-2850 3825);
FORCEPROP 3 LASTPIN (-2900 3825) SIG_NAME M_L_DQS_DP<0>
J 0
(-2890 3835);
DISPLAY 0.659574 (-2890 3835);
PAINT MONO (-2890 3835);
DISPLAY INVISIBLE (-2890 3835);
FORCEPROP 1 LASTPIN (-2900 3825) BN 0
J 2
(-2848 3833);
DISPLAY 0.617021 (-2848 3833);
PAINT GREEN (-2848 3833);
FORCEPROP 2 LAST CDS_LIB mstr_standard
J 0
(-2850 3825);
PAINT MONO (-2850 3825);
DISPLAY INVISIBLE (-2850 3825);
FORCEPROP 1 LAST BODY_TYPE PLUMBING
J 2
(-2850 3775);
DISPLAY 1.595745 (-2850 3775);
PAINT GREEN (-2850 3775);
DISPLAY INVISIBLE (-2850 3775);
FORCEPROP 1 LAST HDL_TAP TRUE
J 2
(-3175 3700);
DISPLAY 1.595745 (-3175 3700);
PAINT GREEN (-3175 3700);
DISPLAY INVISIBLE (-3175 3700);
FORCEPROP 1 LAST PATH I143
J 2
(-2848 3825);
DISPLAY 0.872340 (-2848 3825);
PAINT GREEN (-2848 3825);
DISPLAY INVISIBLE (-2848 3825);
FORCEADD TAP..6
R 2
(-2850 3875);
FORCEPROP 3 LASTPIN (-2900 3875) SIG_NAME M_L_DQS_DP<1>
J 0
(-2890 3885);
DISPLAY 0.659574 (-2890 3885);
PAINT MONO (-2890 3885);
DISPLAY INVISIBLE (-2890 3885);
FORCEPROP 1 LASTPIN (-2900 3875) BN 1
J 2
(-2848 3883);
DISPLAY 0.617021 (-2848 3883);
PAINT GREEN (-2848 3883);
FORCEPROP 2 LAST CDS_LIB mstr_standard
J 0
(-2850 3875);
PAINT MONO (-2850 3875);
DISPLAY INVISIBLE (-2850 3875);
FORCEPROP 1 LAST BODY_TYPE PLUMBING
J 2
(-2850 3825);
DISPLAY 1.595745 (-2850 3825);
PAINT GREEN (-2850 3825);
DISPLAY INVISIBLE (-2850 3825);
FORCEPROP 1 LAST HDL_TAP TRUE
J 2
(-3175 3750);
DISPLAY 1.595745 (-3175 3750);
PAINT GREEN (-3175 3750);
DISPLAY INVISIBLE (-3175 3750);
FORCEPROP 1 LAST PATH I144
J 2
(-2848 3875);
DISPLAY 0.872340 (-2848 3875);
PAINT GREEN (-2848 3875);
DISPLAY INVISIBLE (-2848 3875);
FORCEADD TAP..6
R 2
(-2850 3925);
FORCEPROP 3 LASTPIN (-2900 3925) SIG_NAME M_L_DQS_DP<2>
J 0
(-2890 3935);
DISPLAY 0.659574 (-2890 3935);
PAINT MONO (-2890 3935);
DISPLAY INVISIBLE (-2890 3935);
FORCEPROP 1 LASTPIN (-2900 3925) BN 2
J 2
(-2848 3933);
DISPLAY 0.617021 (-2848 3933);
PAINT GREEN (-2848 3933);
FORCEPROP 2 LAST CDS_LIB mstr_standard
J 0
(-2850 3925);
PAINT MONO (-2850 3925);
DISPLAY INVISIBLE (-2850 3925);
FORCEPROP 1 LAST BODY_TYPE PLUMBING
J 2
(-2850 3875);
DISPLAY 1.595745 (-2850 3875);
PAINT GREEN (-2850 3875);
DISPLAY INVISIBLE (-2850 3875);
FORCEPROP 1 LAST HDL_TAP TRUE
J 2
(-3175 3800);
DISPLAY 1.595745 (-3175 3800);
PAINT GREEN (-3175 3800);
DISPLAY INVISIBLE (-3175 3800);
FORCEPROP 1 LAST PATH I145
J 2
(-2848 3925);
DISPLAY 0.872340 (-2848 3925);
PAINT GREEN (-2848 3925);
DISPLAY INVISIBLE (-2848 3925);
FORCEADD TAP..6
R 2
(-2850 3975);
FORCEPROP 3 LASTPIN (-2900 3975) SIG_NAME M_L_DQS_DP<3>
J 0
(-2890 3985);
DISPLAY 0.659574 (-2890 3985);
PAINT MONO (-2890 3985);
DISPLAY INVISIBLE (-2890 3985);
FORCEPROP 1 LASTPIN (-2900 3975) BN 3
J 2
(-2848 3983);
DISPLAY 0.617021 (-2848 3983);
PAINT GREEN (-2848 3983);
FORCEPROP 2 LAST CDS_LIB mstr_standard
J 0
(-2850 3975);
PAINT MONO (-2850 3975);
DISPLAY INVISIBLE (-2850 3975);
FORCEPROP 1 LAST BODY_TYPE PLUMBING
J 2
(-2850 3925);
DISPLAY 1.595745 (-2850 3925);
PAINT GREEN (-2850 3925);
DISPLAY INVISIBLE (-2850 3925);
FORCEPROP 1 LAST HDL_TAP TRUE
J 2
(-3175 3850);
DISPLAY 1.595745 (-3175 3850);
PAINT GREEN (-3175 3850);
DISPLAY INVISIBLE (-3175 3850);
FORCEPROP 1 LAST PATH I146
J 2
(-2848 3975);
DISPLAY 0.872340 (-2848 3975);
PAINT GREEN (-2848 3975);
DISPLAY INVISIBLE (-2848 3975);
FORCEADD OFFPAGE..2
(-1975 525);
FORCEPROP 2 LAST $XR1 86 
J 0
(-1696 525);
DISPLAY 0.638298 (-1696 525);
PAINT MONO (-1696 525);
FORCEPROP 2 LAST $XR0 85 
J 0
(-1786 525);
DISPLAY 0.638298 (-1786 525);
PAINT MONO (-1786 525);
FORCEPROP 2 LAST CDS_LIB mstr_standard
J 0
(-1975 525);
PAINT MONO (-1975 525);
DISPLAY INVISIBLE (-1975 525);
FORCEPROP 1 LAST OFFPAGE TRUE
J 0
(-1650 400);
DISPLAY 1.170213 (-1650 400);
PAINT GREEN (-1650 400);
DISPLAY INVISIBLE (-1650 400);
FORCEPROP 1 LAST COMMENT_BODY TRUE
J 0
(-2020 430);
DISPLAY 1.170213 (-2020 430);
PAINT GREEN (-2020 430);
DISPLAY INVISIBLE (-2020 430);
FORCEPROP 2 LAST PATH I147
J 0
(-1800 600);
DISPLAY 1.021277 (-1800 600);
PAINT ORANGE (-1800 600);
DISPLAY INVISIBLE (-1800 600);
FORCEADD OFFPAGE..4
(-1975 575);
FORCEPROP 2 LAST $XR1 86 
J 0
(-1699 575);
DISPLAY 0.638298 (-1699 575);
PAINT MONO (-1699 575);
FORCEPROP 2 LAST $XR0 85 
J 0
(-1789 575);
DISPLAY 0.638298 (-1789 575);
PAINT MONO (-1789 575);
FORCEPROP 2 LAST CDS_LIB mstr_standard
J 0
(-1975 575);
PAINT MONO (-1975 575);
DISPLAY INVISIBLE (-1975 575);
FORCEPROP 1 LAST OFFPAGE TRUE
J 0
(-1650 450);
DISPLAY 1.170213 (-1650 450);
PAINT GREEN (-1650 450);
DISPLAY INVISIBLE (-1650 450);
FORCEPROP 1 LAST COMMENT_BODY TRUE
J 0
(-2000 475);
DISPLAY 1.170213 (-2000 475);
PAINT GREEN (-2000 475);
DISPLAY INVISIBLE (-2000 475);
FORCEPROP 2 LAST PATH I148
J 0
(-1800 650);
DISPLAY 1.021277 (-1800 650);
PAINT ORANGE (-1800 650);
DISPLAY INVISIBLE (-1800 650);
FORCEADD OFFPAGE..2
(-1975 625);
FORCEPROP 2 LAST $XR1 86 
J 0
(-1696 625);
DISPLAY 0.638298 (-1696 625);
PAINT MONO (-1696 625);
FORCEPROP 2 LAST $XR0 85 
J 0
(-1786 625);
DISPLAY 0.638298 (-1786 625);
PAINT MONO (-1786 625);
FORCEPROP 2 LAST CDS_LIB mstr_standard
J 0
(-1975 625);
PAINT MONO (-1975 625);
DISPLAY INVISIBLE (-1975 625);
FORCEPROP 1 LAST OFFPAGE TRUE
J 0
(-1650 500);
DISPLAY 1.170213 (-1650 500);
PAINT GREEN (-1650 500);
DISPLAY INVISIBLE (-1650 500);
FORCEPROP 1 LAST COMMENT_BODY TRUE
J 0
(-2020 530);
DISPLAY 1.170213 (-2020 530);
PAINT GREEN (-2020 530);
DISPLAY INVISIBLE (-2020 530);
FORCEPROP 2 LAST PATH I149
J 0
(-1800 700);
DISPLAY 1.021277 (-1800 700);
PAINT ORANGE (-1800 700);
DISPLAY INVISIBLE (-1800 700);
FORCEADD TAP..6
(-5575 1175);
FORCEPROP 3 LASTPIN (-5525 1175) SIG_NAME M_L_ECC<2>
J 0
(-5515 1185);
DISPLAY 0.659574 (-5515 1185);
PAINT MONO (-5515 1185);
DISPLAY INVISIBLE (-5515 1185);
FORCEPROP 1 LASTPIN (-5525 1175) BN 2
J 0
(-5577 1183);
DISPLAY 0.617021 (-5577 1183);
PAINT GREEN (-5577 1183);
FORCEPROP 2 LAST CDS_LIB mstr_standard
J 0
(-5575 1175);
PAINT MONO (-5575 1175);
DISPLAY INVISIBLE (-5575 1175);
FORCEPROP 1 LAST BODY_TYPE PLUMBING
J 0
(-5575 1125);
DISPLAY 1.595745 (-5575 1125);
PAINT GREEN (-5575 1125);
DISPLAY INVISIBLE (-5575 1125);
FORCEPROP 1 LAST HDL_TAP TRUE
J 0
(-5250 1050);
DISPLAY 1.595745 (-5250 1050);
PAINT GREEN (-5250 1050);
DISPLAY INVISIBLE (-5250 1050);
FORCEPROP 1 LAST PATH I15
J 0
(-5577 1175);
DISPLAY 0.872340 (-5577 1175);
PAINT GREEN (-5577 1175);
DISPLAY INVISIBLE (-5577 1175);
FORCEADD OFFPAGE..2
(-2000 825);
FORCEPROP 2 LAST $XR1 86 
J 0
(-1721 825);
DISPLAY 0.638298 (-1721 825);
PAINT MONO (-1721 825);
FORCEPROP 2 LAST $XR0 85 
J 0
(-1811 825);
DISPLAY 0.638298 (-1811 825);
PAINT MONO (-1811 825);
FORCEPROP 2 LAST CDS_LIB mstr_standard
J 0
(-2000 825);
PAINT MONO (-2000 825);
DISPLAY INVISIBLE (-2000 825);
FORCEPROP 1 LAST OFFPAGE TRUE
J 0
(-1675 700);
DISPLAY 1.170213 (-1675 700);
PAINT GREEN (-1675 700);
DISPLAY INVISIBLE (-1675 700);
FORCEPROP 1 LAST COMMENT_BODY TRUE
J 0
(-2045 730);
DISPLAY 1.170213 (-2045 730);
PAINT GREEN (-2045 730);
DISPLAY INVISIBLE (-2045 730);
FORCEPROP 2 LAST PATH I150
J 0
(-1825 900);
DISPLAY 1.021277 (-1825 900);
PAINT ORANGE (-1825 900);
DISPLAY INVISIBLE (-1825 900);
FORCEADD OFFPAGE..2
(-2000 925);
FORCEPROP 2 LAST $XR1 86 
J 0
(-1721 925);
DISPLAY 0.638298 (-1721 925);
PAINT MONO (-1721 925);
FORCEPROP 2 LAST $XR0 85 
J 0
(-1811 925);
DISPLAY 0.638298 (-1811 925);
PAINT MONO (-1811 925);
FORCEPROP 2 LAST CDS_LIB mstr_standard
J 0
(-2000 925);
PAINT MONO (-2000 925);
DISPLAY INVISIBLE (-2000 925);
FORCEPROP 1 LAST OFFPAGE TRUE
J 0
(-1675 800);
DISPLAY 1.170213 (-1675 800);
PAINT GREEN (-1675 800);
DISPLAY INVISIBLE (-1675 800);
FORCEPROP 1 LAST COMMENT_BODY TRUE
J 0
(-2045 830);
DISPLAY 1.170213 (-2045 830);
PAINT GREEN (-2045 830);
DISPLAY INVISIBLE (-2045 830);
FORCEPROP 2 LAST PATH I151
J 0
(-1825 1000);
DISPLAY 1.021277 (-1825 1000);
PAINT ORANGE (-1825 1000);
DISPLAY INVISIBLE (-1825 1000);
FORCEADD OFFPAGE..2
(-2000 1375);
FORCEPROP 2 LAST $XR1 86 
J 0
(-1721 1375);
DISPLAY 0.638298 (-1721 1375);
PAINT MONO (-1721 1375);
FORCEPROP 2 LAST $XR0 85 
J 0
(-1811 1375);
DISPLAY 0.638298 (-1811 1375);
PAINT MONO (-1811 1375);
FORCEPROP 2 LAST CDS_LIB mstr_standard
J 0
(-2000 1375);
PAINT MONO (-2000 1375);
DISPLAY INVISIBLE (-2000 1375);
FORCEPROP 1 LAST OFFPAGE TRUE
J 0
(-1675 1250);
DISPLAY 1.170213 (-1675 1250);
PAINT GREEN (-1675 1250);
DISPLAY INVISIBLE (-1675 1250);
FORCEPROP 1 LAST COMMENT_BODY TRUE
J 0
(-2045 1280);
DISPLAY 1.170213 (-2045 1280);
PAINT GREEN (-2045 1280);
DISPLAY INVISIBLE (-2045 1280);
FORCEPROP 2 LAST PATH I152
J 0
(-1825 1450);
DISPLAY 1.021277 (-1825 1450);
PAINT ORANGE (-1825 1450);
DISPLAY INVISIBLE (-1825 1450);
FORCEADD OFFPAGE..2
(-2000 1625);
FORCEPROP 2 LAST $XR1 86 
J 0
(-1721 1625);
DISPLAY 0.638298 (-1721 1625);
PAINT MONO (-1721 1625);
FORCEPROP 2 LAST $XR0 85 
J 0
(-1811 1625);
DISPLAY 0.638298 (-1811 1625);
PAINT MONO (-1811 1625);
FORCEPROP 2 LAST CDS_LIB mstr_standard
J 0
(-2000 1625);
PAINT MONO (-2000 1625);
DISPLAY INVISIBLE (-2000 1625);
FORCEPROP 1 LAST OFFPAGE TRUE
J 0
(-1675 1500);
DISPLAY 1.170213 (-1675 1500);
PAINT GREEN (-1675 1500);
DISPLAY INVISIBLE (-1675 1500);
FORCEPROP 1 LAST COMMENT_BODY TRUE
J 0
(-2045 1530);
DISPLAY 1.170213 (-2045 1530);
PAINT GREEN (-2045 1530);
DISPLAY INVISIBLE (-2045 1530);
FORCEPROP 2 LAST PATH I153
J 0
(-1825 1700);
DISPLAY 1.021277 (-1825 1700);
PAINT ORANGE (-1825 1700);
DISPLAY INVISIBLE (-1825 1700);
FORCEADD OFFPAGE..2
(-2000 1875);
FORCEPROP 2 LAST $XR1 86 
J 0
(-1721 1875);
DISPLAY 0.638298 (-1721 1875);
PAINT MONO (-1721 1875);
FORCEPROP 2 LAST $XR0 85 
J 0
(-1811 1875);
DISPLAY 0.638298 (-1811 1875);
PAINT MONO (-1811 1875);
FORCEPROP 2 LAST CDS_LIB mstr_standard
J 0
(-2000 1875);
PAINT MONO (-2000 1875);
DISPLAY INVISIBLE (-2000 1875);
FORCEPROP 1 LAST OFFPAGE TRUE
J 0
(-1675 1750);
DISPLAY 1.170213 (-1675 1750);
PAINT GREEN (-1675 1750);
DISPLAY INVISIBLE (-1675 1750);
FORCEPROP 1 LAST COMMENT_BODY TRUE
J 0
(-2045 1780);
DISPLAY 1.170213 (-2045 1780);
PAINT GREEN (-2045 1780);
DISPLAY INVISIBLE (-2045 1780);
FORCEPROP 2 LAST PATH I154
J 0
(-1825 1950);
DISPLAY 1.021277 (-1825 1950);
PAINT ORANGE (-1825 1950);
DISPLAY INVISIBLE (-1825 1950);
FORCEADD OFFPAGE..2
(-2000 2825);
FORCEPROP 2 LAST $XR1 86 
J 0
(-1721 2825);
DISPLAY 0.638298 (-1721 2825);
PAINT MONO (-1721 2825);
FORCEPROP 2 LAST $XR0 85 
J 0
(-1811 2825);
DISPLAY 0.638298 (-1811 2825);
PAINT MONO (-1811 2825);
FORCEPROP 2 LAST CDS_LIB mstr_standard
J 0
(-2000 2825);
PAINT MONO (-2000 2825);
DISPLAY INVISIBLE (-2000 2825);
FORCEPROP 1 LAST OFFPAGE TRUE
J 0
(-1675 2700);
DISPLAY 1.170213 (-1675 2700);
PAINT GREEN (-1675 2700);
DISPLAY INVISIBLE (-1675 2700);
FORCEPROP 1 LAST COMMENT_BODY TRUE
J 0
(-2045 2730);
DISPLAY 1.170213 (-2045 2730);
PAINT GREEN (-2045 2730);
DISPLAY INVISIBLE (-2045 2730);
FORCEPROP 2 LAST PATH I155
J 0
(-1825 2900);
DISPLAY 1.021277 (-1825 2900);
PAINT ORANGE (-1825 2900);
DISPLAY INVISIBLE (-1825 2900);
FORCEADD OFFPAGE..3
(-2000 3775);
FORCEPROP 2 LAST $XR1 86 
J 0
(-1696 3775);
DISPLAY 0.638298 (-1696 3775);
PAINT MONO (-1696 3775);
FORCEPROP 2 LAST $XR0 85 
J 0
(-1786 3775);
DISPLAY 0.638298 (-1786 3775);
PAINT MONO (-1786 3775);
FORCEPROP 2 LAST CDS_LIB mstr_standard
J 0
(-2000 3775);
PAINT MONO (-2000 3775);
DISPLAY INVISIBLE (-2000 3775);
FORCEPROP 1 LAST OFFPAGE TRUE
J 0
(-1675 3650);
DISPLAY 1.170213 (-1675 3650);
PAINT GREEN (-1675 3650);
DISPLAY INVISIBLE (-1675 3650);
FORCEPROP 1 LAST COMMENT_BODY TRUE
J 0
(-2050 3675);
DISPLAY 1.170213 (-2050 3675);
PAINT GREEN (-2050 3675);
DISPLAY INVISIBLE (-2050 3675);
FORCEPROP 2 LAST PATH I156
J 0
(-1800 3850);
DISPLAY 1.021277 (-1800 3850);
PAINT ORANGE (-1800 3850);
DISPLAY INVISIBLE (-1800 3850);
FORCEADD TAP..6
R 2
(-2850 4025);
FORCEPROP 3 LASTPIN (-2900 4025) SIG_NAME M_L_DQS_DP<4>
J 0
(-2890 4035);
DISPLAY 0.659574 (-2890 4035);
PAINT MONO (-2890 4035);
DISPLAY INVISIBLE (-2890 4035);
FORCEPROP 1 LASTPIN (-2900 4025) BN 4
J 2
(-2848 4033);
DISPLAY 0.617021 (-2848 4033);
PAINT GREEN (-2848 4033);
FORCEPROP 2 LAST CDS_LIB mstr_standard
J 0
(-2850 4025);
PAINT MONO (-2850 4025);
DISPLAY INVISIBLE (-2850 4025);
FORCEPROP 1 LAST BODY_TYPE PLUMBING
J 2
(-2850 3975);
DISPLAY 1.595745 (-2850 3975);
PAINT GREEN (-2850 3975);
DISPLAY INVISIBLE (-2850 3975);
FORCEPROP 1 LAST HDL_TAP TRUE
J 2
(-3175 3900);
DISPLAY 1.595745 (-3175 3900);
PAINT GREEN (-3175 3900);
DISPLAY INVISIBLE (-3175 3900);
FORCEPROP 1 LAST PATH I157
J 2
(-2848 4025);
DISPLAY 0.872340 (-2848 4025);
PAINT GREEN (-2848 4025);
DISPLAY INVISIBLE (-2848 4025);
FORCEADD TAP..6
R 2
(-2850 4125);
FORCEPROP 3 LASTPIN (-2900 4125) SIG_NAME M_L_DQS_DP<6>
J 0
(-2890 4135);
DISPLAY 0.659574 (-2890 4135);
PAINT MONO (-2890 4135);
DISPLAY INVISIBLE (-2890 4135);
FORCEPROP 1 LASTPIN (-2900 4125) BN 6
J 2
(-2848 4133);
DISPLAY 0.617021 (-2848 4133);
PAINT GREEN (-2848 4133);
FORCEPROP 2 LAST CDS_LIB mstr_standard
J 0
(-2850 4125);
PAINT MONO (-2850 4125);
DISPLAY INVISIBLE (-2850 4125);
FORCEPROP 1 LAST BODY_TYPE PLUMBING
J 2
(-2850 4075);
DISPLAY 1.595745 (-2850 4075);
PAINT GREEN (-2850 4075);
DISPLAY INVISIBLE (-2850 4075);
FORCEPROP 1 LAST HDL_TAP TRUE
J 2
(-3175 4000);
DISPLAY 1.595745 (-3175 4000);
PAINT GREEN (-3175 4000);
DISPLAY INVISIBLE (-3175 4000);
FORCEPROP 1 LAST PATH I158
J 2
(-2848 4125);
DISPLAY 0.872340 (-2848 4125);
PAINT GREEN (-2848 4125);
DISPLAY INVISIBLE (-2848 4125);
FORCEADD TAP..6
R 2
(-2850 4075);
FORCEPROP 3 LASTPIN (-2900 4075) SIG_NAME M_L_DQS_DP<5>
J 0
(-2890 4085);
DISPLAY 0.659574 (-2890 4085);
PAINT MONO (-2890 4085);
DISPLAY INVISIBLE (-2890 4085);
FORCEPROP 1 LASTPIN (-2900 4075) BN 5
J 2
(-2848 4083);
DISPLAY 0.617021 (-2848 4083);
PAINT GREEN (-2848 4083);
FORCEPROP 2 LAST CDS_LIB mstr_standard
J 0
(-2850 4075);
PAINT MONO (-2850 4075);
DISPLAY INVISIBLE (-2850 4075);
FORCEPROP 1 LAST BODY_TYPE PLUMBING
J 2
(-2850 4025);
DISPLAY 1.595745 (-2850 4025);
PAINT GREEN (-2850 4025);
DISPLAY INVISIBLE (-2850 4025);
FORCEPROP 1 LAST HDL_TAP TRUE
J 2
(-3175 3950);
DISPLAY 1.595745 (-3175 3950);
PAINT GREEN (-3175 3950);
DISPLAY INVISIBLE (-3175 3950);
FORCEPROP 1 LAST PATH I159
J 2
(-2848 4075);
DISPLAY 0.872340 (-2848 4075);
PAINT GREEN (-2848 4075);
DISPLAY INVISIBLE (-2848 4075);
FORCEADD TAP..6
(-5575 1275);
FORCEPROP 3 LASTPIN (-5525 1275) SIG_NAME M_L_ECC<4>
J 0
(-5515 1285);
DISPLAY 0.659574 (-5515 1285);
PAINT MONO (-5515 1285);
DISPLAY INVISIBLE (-5515 1285);
FORCEPROP 1 LASTPIN (-5525 1275) BN 4
J 0
(-5577 1283);
DISPLAY 0.617021 (-5577 1283);
PAINT GREEN (-5577 1283);
FORCEPROP 2 LAST CDS_LIB mstr_standard
J 0
(-5575 1275);
PAINT MONO (-5575 1275);
DISPLAY INVISIBLE (-5575 1275);
FORCEPROP 1 LAST BODY_TYPE PLUMBING
J 0
(-5575 1225);
DISPLAY 1.595745 (-5575 1225);
PAINT GREEN (-5575 1225);
DISPLAY INVISIBLE (-5575 1225);
FORCEPROP 1 LAST HDL_TAP TRUE
J 0
(-5250 1150);
DISPLAY 1.595745 (-5250 1150);
PAINT GREEN (-5250 1150);
DISPLAY INVISIBLE (-5250 1150);
FORCEPROP 1 LAST PATH I16
J 0
(-5577 1275);
DISPLAY 0.872340 (-5577 1275);
PAINT GREEN (-5577 1275);
DISPLAY INVISIBLE (-5577 1275);
FORCEADD TAP..6
R 2
(-2850 4175);
FORCEPROP 3 LASTPIN (-2900 4175) SIG_NAME M_L_DQS_DP<7>
J 0
(-2890 4185);
DISPLAY 0.659574 (-2890 4185);
PAINT MONO (-2890 4185);
DISPLAY INVISIBLE (-2890 4185);
FORCEPROP 1 LASTPIN (-2900 4175) BN 7
J 2
(-2848 4183);
DISPLAY 0.617021 (-2848 4183);
PAINT GREEN (-2848 4183);
FORCEPROP 2 LAST CDS_LIB mstr_standard
J 0
(-2850 4175);
PAINT MONO (-2850 4175);
DISPLAY INVISIBLE (-2850 4175);
FORCEPROP 1 LAST BODY_TYPE PLUMBING
J 2
(-2850 4125);
DISPLAY 1.595745 (-2850 4125);
PAINT GREEN (-2850 4125);
DISPLAY INVISIBLE (-2850 4125);
FORCEPROP 1 LAST HDL_TAP TRUE
J 2
(-3175 4050);
DISPLAY 1.595745 (-3175 4050);
PAINT GREEN (-3175 4050);
DISPLAY INVISIBLE (-3175 4050);
FORCEPROP 1 LAST PATH I160
J 2
(-2848 4175);
DISPLAY 0.872340 (-2848 4175);
PAINT GREEN (-2848 4175);
DISPLAY INVISIBLE (-2848 4175);
FORCEADD TAP..6
R 2
(-2850 4225);
FORCEPROP 3 LASTPIN (-2900 4225) SIG_NAME M_L_DQS_DP<8>
J 0
(-2890 4235);
DISPLAY 0.659574 (-2890 4235);
PAINT MONO (-2890 4235);
DISPLAY INVISIBLE (-2890 4235);
FORCEPROP 1 LASTPIN (-2900 4225) BN 8
J 2
(-2848 4233);
DISPLAY 0.617021 (-2848 4233);
PAINT GREEN (-2848 4233);
FORCEPROP 2 LAST CDS_LIB mstr_standard
J 0
(-2850 4225);
PAINT MONO (-2850 4225);
DISPLAY INVISIBLE (-2850 4225);
FORCEPROP 1 LAST BODY_TYPE PLUMBING
J 2
(-2850 4175);
DISPLAY 1.595745 (-2850 4175);
PAINT GREEN (-2850 4175);
DISPLAY INVISIBLE (-2850 4175);
FORCEPROP 1 LAST HDL_TAP TRUE
J 2
(-3175 4100);
DISPLAY 1.595745 (-3175 4100);
PAINT GREEN (-3175 4100);
DISPLAY INVISIBLE (-3175 4100);
FORCEPROP 1 LAST PATH I161
J 2
(-2848 4225);
DISPLAY 0.872340 (-2848 4225);
PAINT GREEN (-2848 4225);
DISPLAY INVISIBLE (-2848 4225);
FORCEADD TAP..6
R 2
(-2850 4275);
FORCEPROP 3 LASTPIN (-2900 4275) SIG_NAME M_L_DQS_DP<9>
J 0
(-2890 4285);
DISPLAY 0.659574 (-2890 4285);
PAINT MONO (-2890 4285);
DISPLAY INVISIBLE (-2890 4285);
FORCEPROP 1 LASTPIN (-2900 4275) BN 9
J 2
(-2848 4283);
DISPLAY 0.617021 (-2848 4283);
PAINT GREEN (-2848 4283);
FORCEPROP 2 LAST CDS_LIB mstr_standard
J 0
(-2850 4275);
PAINT MONO (-2850 4275);
DISPLAY INVISIBLE (-2850 4275);
FORCEPROP 1 LAST BODY_TYPE PLUMBING
J 2
(-2850 4225);
DISPLAY 1.595745 (-2850 4225);
PAINT GREEN (-2850 4225);
DISPLAY INVISIBLE (-2850 4225);
FORCEPROP 1 LAST HDL_TAP TRUE
J 2
(-3175 4150);
DISPLAY 1.595745 (-3175 4150);
PAINT GREEN (-3175 4150);
DISPLAY INVISIBLE (-3175 4150);
FORCEPROP 1 LAST PATH I162
J 2
(-2848 4275);
DISPLAY 0.872340 (-2848 4275);
PAINT GREEN (-2848 4275);
DISPLAY INVISIBLE (-2848 4275);
FORCEADD TAP..6
R 2
(-2850 4325);
FORCEPROP 3 LASTPIN (-2900 4325) SIG_NAME M_L_DQS_DP<10>
J 0
(-2890 4335);
DISPLAY 0.659574 (-2890 4335);
PAINT MONO (-2890 4335);
DISPLAY INVISIBLE (-2890 4335);
FORCEPROP 1 LASTPIN (-2900 4325) BN 10
J 2
(-2848 4333);
DISPLAY 0.617021 (-2848 4333);
PAINT GREEN (-2848 4333);
FORCEPROP 2 LAST CDS_LIB mstr_standard
J 0
(-2850 4325);
PAINT MONO (-2850 4325);
DISPLAY INVISIBLE (-2850 4325);
FORCEPROP 1 LAST BODY_TYPE PLUMBING
J 2
(-2850 4275);
DISPLAY 1.595745 (-2850 4275);
PAINT GREEN (-2850 4275);
DISPLAY INVISIBLE (-2850 4275);
FORCEPROP 1 LAST HDL_TAP TRUE
J 2
(-3175 4200);
DISPLAY 1.595745 (-3175 4200);
PAINT GREEN (-3175 4200);
DISPLAY INVISIBLE (-3175 4200);
FORCEPROP 1 LAST PATH I163
J 2
(-2848 4325);
DISPLAY 0.872340 (-2848 4325);
PAINT GREEN (-2848 4325);
DISPLAY INVISIBLE (-2848 4325);
FORCEADD TAP..6
R 2
(-2850 4375);
FORCEPROP 3 LASTPIN (-2900 4375) SIG_NAME M_L_DQS_DP<11>
J 0
(-2890 4385);
DISPLAY 0.659574 (-2890 4385);
PAINT MONO (-2890 4385);
DISPLAY INVISIBLE (-2890 4385);
FORCEPROP 1 LASTPIN (-2900 4375) BN 11
J 2
(-2848 4383);
DISPLAY 0.617021 (-2848 4383);
PAINT GREEN (-2848 4383);
FORCEPROP 2 LAST CDS_LIB mstr_standard
J 0
(-2850 4375);
PAINT MONO (-2850 4375);
DISPLAY INVISIBLE (-2850 4375);
FORCEPROP 1 LAST BODY_TYPE PLUMBING
J 2
(-2850 4325);
DISPLAY 1.595745 (-2850 4325);
PAINT GREEN (-2850 4325);
DISPLAY INVISIBLE (-2850 4325);
FORCEPROP 1 LAST HDL_TAP TRUE
J 2
(-3175 4250);
DISPLAY 1.595745 (-3175 4250);
PAINT GREEN (-3175 4250);
DISPLAY INVISIBLE (-3175 4250);
FORCEPROP 1 LAST PATH I164
J 2
(-2848 4375);
DISPLAY 0.872340 (-2848 4375);
PAINT GREEN (-2848 4375);
DISPLAY INVISIBLE (-2848 4375);
FORCEADD TAP..6
R 2
(-2850 4525);
FORCEPROP 3 LASTPIN (-2900 4525) SIG_NAME M_L_DQS_DP<14>
J 0
(-2890 4535);
DISPLAY 0.659574 (-2890 4535);
PAINT MONO (-2890 4535);
DISPLAY INVISIBLE (-2890 4535);
FORCEPROP 1 LASTPIN (-2900 4525) BN 14
J 2
(-2848 4533);
DISPLAY 0.617021 (-2848 4533);
PAINT GREEN (-2848 4533);
FORCEPROP 2 LAST CDS_LIB mstr_standard
J 0
(-2850 4525);
PAINT MONO (-2850 4525);
DISPLAY INVISIBLE (-2850 4525);
FORCEPROP 1 LAST BODY_TYPE PLUMBING
J 2
(-2850 4475);
DISPLAY 1.595745 (-2850 4475);
PAINT GREEN (-2850 4475);
DISPLAY INVISIBLE (-2850 4475);
FORCEPROP 1 LAST HDL_TAP TRUE
J 2
(-3175 4400);
DISPLAY 1.595745 (-3175 4400);
PAINT GREEN (-3175 4400);
DISPLAY INVISIBLE (-3175 4400);
FORCEPROP 1 LAST PATH I165
J 2
(-2848 4525);
DISPLAY 0.872340 (-2848 4525);
PAINT GREEN (-2848 4525);
DISPLAY INVISIBLE (-2848 4525);
FORCEADD TAP..6
R 2
(-2850 4475);
FORCEPROP 3 LASTPIN (-2900 4475) SIG_NAME M_L_DQS_DP<13>
J 0
(-2890 4485);
DISPLAY 0.659574 (-2890 4485);
PAINT MONO (-2890 4485);
DISPLAY INVISIBLE (-2890 4485);
FORCEPROP 1 LASTPIN (-2900 4475) BN 13
J 2
(-2848 4483);
DISPLAY 0.617021 (-2848 4483);
PAINT GREEN (-2848 4483);
FORCEPROP 2 LAST CDS_LIB mstr_standard
J 0
(-2850 4475);
PAINT MONO (-2850 4475);
DISPLAY INVISIBLE (-2850 4475);
FORCEPROP 1 LAST BODY_TYPE PLUMBING
J 2
(-2850 4425);
DISPLAY 1.595745 (-2850 4425);
PAINT GREEN (-2850 4425);
DISPLAY INVISIBLE (-2850 4425);
FORCEPROP 1 LAST HDL_TAP TRUE
J 2
(-3175 4350);
DISPLAY 1.595745 (-3175 4350);
PAINT GREEN (-3175 4350);
DISPLAY INVISIBLE (-3175 4350);
FORCEPROP 1 LAST PATH I166
J 2
(-2848 4475);
DISPLAY 0.872340 (-2848 4475);
PAINT GREEN (-2848 4475);
DISPLAY INVISIBLE (-2848 4475);
FORCEADD TAP..6
R 2
(-2850 4425);
FORCEPROP 3 LASTPIN (-2900 4425) SIG_NAME M_L_DQS_DP<12>
J 0
(-2890 4435);
DISPLAY 0.659574 (-2890 4435);
PAINT MONO (-2890 4435);
DISPLAY INVISIBLE (-2890 4435);
FORCEPROP 1 LASTPIN (-2900 4425) BN 12
J 2
(-2848 4433);
DISPLAY 0.617021 (-2848 4433);
PAINT GREEN (-2848 4433);
FORCEPROP 2 LAST CDS_LIB mstr_standard
J 0
(-2850 4425);
PAINT MONO (-2850 4425);
DISPLAY INVISIBLE (-2850 4425);
FORCEPROP 1 LAST BODY_TYPE PLUMBING
J 2
(-2850 4375);
DISPLAY 1.595745 (-2850 4375);
PAINT GREEN (-2850 4375);
DISPLAY INVISIBLE (-2850 4375);
FORCEPROP 1 LAST HDL_TAP TRUE
J 2
(-3175 4300);
DISPLAY 1.595745 (-3175 4300);
PAINT GREEN (-3175 4300);
DISPLAY INVISIBLE (-3175 4300);
FORCEPROP 1 LAST PATH I167
J 2
(-2848 4425);
DISPLAY 0.872340 (-2848 4425);
PAINT GREEN (-2848 4425);
DISPLAY INVISIBLE (-2848 4425);
FORCEADD TAP..6
R 2
(-2850 4575);
FORCEPROP 3 LASTPIN (-2900 4575) SIG_NAME M_L_DQS_DP<15>
J 0
(-2890 4585);
DISPLAY 0.659574 (-2890 4585);
PAINT MONO (-2890 4585);
DISPLAY INVISIBLE (-2890 4585);
FORCEPROP 1 LASTPIN (-2900 4575) BN 15
J 2
(-2848 4583);
DISPLAY 0.617021 (-2848 4583);
PAINT GREEN (-2848 4583);
FORCEPROP 2 LAST CDS_LIB mstr_standard
J 0
(-2850 4575);
PAINT MONO (-2850 4575);
DISPLAY INVISIBLE (-2850 4575);
FORCEPROP 1 LAST BODY_TYPE PLUMBING
J 2
(-2850 4525);
DISPLAY 1.595745 (-2850 4525);
PAINT GREEN (-2850 4525);
DISPLAY INVISIBLE (-2850 4525);
FORCEPROP 1 LAST HDL_TAP TRUE
J 2
(-3175 4450);
DISPLAY 1.595745 (-3175 4450);
PAINT GREEN (-3175 4450);
DISPLAY INVISIBLE (-3175 4450);
FORCEPROP 1 LAST PATH I168
J 2
(-2848 4575);
DISPLAY 0.872340 (-2848 4575);
PAINT GREEN (-2848 4575);
DISPLAY INVISIBLE (-2848 4575);
FORCEADD TAP..6
R 2
(-2850 4625);
FORCEPROP 3 LASTPIN (-2900 4625) SIG_NAME M_L_DQS_DP<16>
J 0
(-2890 4635);
DISPLAY 0.659574 (-2890 4635);
PAINT MONO (-2890 4635);
DISPLAY INVISIBLE (-2890 4635);
FORCEPROP 1 LASTPIN (-2900 4625) BN 16
J 2
(-2848 4633);
DISPLAY 0.617021 (-2848 4633);
PAINT GREEN (-2848 4633);
FORCEPROP 2 LAST CDS_LIB mstr_standard
J 0
(-2850 4625);
PAINT MONO (-2850 4625);
DISPLAY INVISIBLE (-2850 4625);
FORCEPROP 1 LAST BODY_TYPE PLUMBING
J 2
(-2850 4575);
DISPLAY 1.595745 (-2850 4575);
PAINT GREEN (-2850 4575);
DISPLAY INVISIBLE (-2850 4575);
FORCEPROP 1 LAST HDL_TAP TRUE
J 2
(-3175 4500);
DISPLAY 1.595745 (-3175 4500);
PAINT GREEN (-3175 4500);
DISPLAY INVISIBLE (-3175 4500);
FORCEPROP 1 LAST PATH I169
J 2
(-2848 4625);
DISPLAY 0.872340 (-2848 4625);
PAINT GREEN (-2848 4625);
DISPLAY INVISIBLE (-2848 4625);
FORCEADD TAP..6
(-5575 1225);
FORCEPROP 3 LASTPIN (-5525 1225) SIG_NAME M_L_ECC<3>
J 0
(-5515 1235);
DISPLAY 0.659574 (-5515 1235);
PAINT MONO (-5515 1235);
DISPLAY INVISIBLE (-5515 1235);
FORCEPROP 1 LASTPIN (-5525 1225) BN 3
J 0
(-5577 1233);
DISPLAY 0.617021 (-5577 1233);
PAINT GREEN (-5577 1233);
FORCEPROP 2 LAST CDS_LIB mstr_standard
J 0
(-5575 1225);
PAINT MONO (-5575 1225);
DISPLAY INVISIBLE (-5575 1225);
FORCEPROP 1 LAST BODY_TYPE PLUMBING
J 0
(-5575 1175);
DISPLAY 1.595745 (-5575 1175);
PAINT GREEN (-5575 1175);
DISPLAY INVISIBLE (-5575 1175);
FORCEPROP 1 LAST HDL_TAP TRUE
J 0
(-5250 1100);
DISPLAY 1.595745 (-5250 1100);
PAINT GREEN (-5250 1100);
DISPLAY INVISIBLE (-5250 1100);
FORCEPROP 1 LAST PATH I17
J 0
(-5577 1225);
DISPLAY 0.872340 (-5577 1225);
PAINT GREEN (-5577 1225);
DISPLAY INVISIBLE (-5577 1225);
FORCEADD TAP..6
R 2
(-2850 4675);
FORCEPROP 3 LASTPIN (-2900 4675) SIG_NAME M_L_DQS_DP<17>
J 0
(-2890 4685);
DISPLAY 0.659574 (-2890 4685);
PAINT MONO (-2890 4685);
DISPLAY INVISIBLE (-2890 4685);
FORCEPROP 1 LASTPIN (-2900 4675) BN 17
J 2
(-2848 4683);
DISPLAY 0.617021 (-2848 4683);
PAINT GREEN (-2848 4683);
FORCEPROP 2 LAST CDS_LIB mstr_standard
J 2
(-2850 4675);
PAINT MONO (-2850 4675);
DISPLAY INVISIBLE (-2850 4675);
FORCEPROP 1 LAST BODY_TYPE PLUMBING
J 2
(-2850 4625);
DISPLAY 1.595745 (-2850 4625);
PAINT GREEN (-2850 4625);
DISPLAY INVISIBLE (-2850 4625);
FORCEPROP 1 LAST HDL_TAP TRUE
J 2
(-3175 4550);
DISPLAY 1.595745 (-3175 4550);
PAINT GREEN (-3175 4550);
DISPLAY INVISIBLE (-3175 4550);
FORCEPROP 1 LAST PATH I170
J 2
(-2848 4675);
DISPLAY 0.872340 (-2848 4675);
PAINT GREEN (-2848 4675);
DISPLAY INVISIBLE (-2848 4675);
FORCEADD OFFPAGE..3
(-2000 4750);
FORCEPROP 2 LAST $XR1 86 
J 0
(-1696 4750);
DISPLAY 0.638298 (-1696 4750);
PAINT MONO (-1696 4750);
FORCEPROP 2 LAST $XR0 85 
J 0
(-1786 4750);
DISPLAY 0.638298 (-1786 4750);
PAINT MONO (-1786 4750);
FORCEPROP 2 LAST CDS_LIB mstr_standard
J 0
(-2000 4750);
PAINT MONO (-2000 4750);
DISPLAY INVISIBLE (-2000 4750);
FORCEPROP 1 LAST OFFPAGE TRUE
J 0
(-1675 4625);
DISPLAY 1.170213 (-1675 4625);
PAINT GREEN (-1675 4625);
DISPLAY INVISIBLE (-1675 4625);
FORCEPROP 1 LAST COMMENT_BODY TRUE
J 0
(-2050 4650);
DISPLAY 1.170213 (-2050 4650);
PAINT GREEN (-2050 4650);
DISPLAY INVISIBLE (-2050 4650);
FORCEPROP 2 LAST PATH I171
J 0
(-1800 4825);
DISPLAY 1.021277 (-1800 4825);
PAINT ORANGE (-1800 4825);
DISPLAY INVISIBLE (-1800 4825);
FORCEADD SKX_EXT_B..7
(-4175 2575);
FORCEPROP 1 LAST LOCATION U2D1
J 0
(-4975 4925);
DISPLAY 0.617021 (-4975 4925);
PAINT AQUA (-4975 4925);
FORCEPROP 1 LAST PART_NUMBER TBD
J 0
(-4975 325);
DISPLAY 0.617021 (-4975 325);
PAINT BLUE (-4975 325);
FORCEPROP 1 LAST MATERIAL IC
J 0
(-4975 4875);
DISPLAY 0.617021 (-4975 4875);
PAINT SKYBLUE (-4975 4875);
FORCEPROP 2 LASTPIN (-3325 525) $PN DV53
J 0
(-3315 535);
DISPLAY 0.617021 (-3315 535);
PAINT ORANGE (-3315 535);
FORCEPROP 2 LASTPIN (-3325 1575) $PN DM47
J 0
(-3315 1585);
DISPLAY 0.617021 (-3315 1585);
PAINT ORANGE (-3315 1585);
FORCEPROP 2 LASTPIN (-3325 1525) $PN DT49
J 0
(-3315 1535);
DISPLAY 0.617021 (-3315 1535);
PAINT ORANGE (-3315 1535);
FORCEPROP 2 LASTPIN (-3325 1475) $PN DN48
J 0
(-3315 1485);
DISPLAY 0.617021 (-3315 1485);
PAINT ORANGE (-3315 1485);
FORCEPROP 2 LASTPIN (-3325 1425) $PN DR50
J 0
(-3315 1435);
DISPLAY 0.617021 (-3315 1435);
PAINT ORANGE (-3315 1435);
FORCEPROP 2 LASTPIN (-3325 2775) $PN DR48
J 0
(-3315 2785);
DISPLAY 0.617021 (-3315 2785);
PAINT ORANGE (-3315 2785);
FORCEPROP 2 LASTPIN (-3325 2725) $PN DN52
J 0
(-3315 2735);
DISPLAY 0.617021 (-3315 2735);
PAINT ORANGE (-3315 2735);
FORCEPROP 2 LASTPIN (-3325 2675) $PN DR52
J 0
(-3315 2685);
DISPLAY 0.617021 (-3315 2685);
PAINT ORANGE (-3315 2685);
FORCEPROP 2 LASTPIN (-3325 2625) $PN DM51
J 0
(-3315 2635);
DISPLAY 0.617021 (-3315 2635);
PAINT ORANGE (-3315 2635);
FORCEPROP 2 LASTPIN (-3325 2575) $PN DT51
J 0
(-3315 2585);
DISPLAY 0.617021 (-3315 2585);
PAINT ORANGE (-3315 2585);
FORCEPROP 2 LASTPIN (-3325 2525) $PN DN60
J 0
(-3315 2535);
DISPLAY 0.617021 (-3315 2535);
PAINT ORANGE (-3315 2535);
FORCEPROP 2 LASTPIN (-3325 2475) $PN DR60
J 0
(-3315 2485);
DISPLAY 0.617021 (-3315 2485);
PAINT ORANGE (-3315 2485);
FORCEPROP 2 LASTPIN (-3325 2425) $PN DT55
J 0
(-3315 2435);
DISPLAY 0.617021 (-3315 2435);
PAINT ORANGE (-3315 2435);
FORCEPROP 2 LASTPIN (-3325 2375) $PN DV59
J 0
(-3315 2385);
DISPLAY 0.617021 (-3315 2385);
PAINT ORANGE (-3315 2385);
FORCEPROP 2 LASTPIN (-3325 2325) $PN DJ60
J 0
(-3315 2335);
DISPLAY 0.617021 (-3315 2335);
PAINT ORANGE (-3315 2335);
FORCEPROP 2 LASTPIN (-3325 2275) $PN DK61
J 0
(-3315 2285);
DISPLAY 0.617021 (-3315 2285);
PAINT ORANGE (-3315 2285);
FORCEPROP 2 LASTPIN (-3325 2225) $PN DM59
J 0
(-3315 2235);
DISPLAY 0.617021 (-3315 2235);
PAINT ORANGE (-3315 2235);
FORCEPROP 2 LASTPIN (-3325 2175) $PN DN58
J 0
(-3315 2185);
DISPLAY 0.617021 (-3315 2185);
PAINT ORANGE (-3315 2185);
FORCEPROP 2 LASTPIN (-3325 2125) $PN DT59
J 0
(-3315 2135);
DISPLAY 0.617021 (-3315 2135);
PAINT ORANGE (-3315 2135);
FORCEPROP 2 LASTPIN (-3325 2075) $PN DR58
J 0
(-3315 2085);
DISPLAY 0.617021 (-3315 2085);
PAINT ORANGE (-3315 2085);
FORCEPROP 2 LASTPIN (-3325 2025) $PN DV57
J 0
(-3315 2035);
DISPLAY 0.617021 (-3315 2035);
PAINT ORANGE (-3315 2035);
FORCEPROP 2 LASTPIN (-3325 1975) $PN DW58
J 0
(-3315 1985);
DISPLAY 0.617021 (-3315 1985);
PAINT ORANGE (-3315 1985);
FORCEPROP 2 LASTPIN (-3325 1925) $PN DW52
J 0
(-3315 1935);
DISPLAY 0.617021 (-3315 1935);
PAINT ORANGE (-3315 1935);
FORCEPROP 2 LASTPIN (-5025 1425) $PN EA66
J 2
(-5035 1435);
DISPLAY 0.617021 (-5035 1435);
PAINT ORANGE (-5035 1435);
FORCEPROP 2 LASTPIN (-5025 1375) $PN DU66
J 2
(-5035 1385);
DISPLAY 0.617021 (-5035 1385);
PAINT ORANGE (-5035 1385);
FORCEPROP 2 LASTPIN (-5025 1325) $PN DV69
J 2
(-5035 1335);
DISPLAY 0.617021 (-5035 1335);
PAINT ORANGE (-5035 1335);
FORCEPROP 2 LASTPIN (-5025 1275) $PN DU68
J 2
(-5035 1285);
DISPLAY 0.617021 (-5035 1285);
PAINT ORANGE (-5035 1285);
FORCEPROP 2 LASTPIN (-5025 1225) $PN DY65
J 2
(-5035 1235);
DISPLAY 0.617021 (-5035 1235);
PAINT ORANGE (-5035 1235);
FORCEPROP 2 LASTPIN (-5025 1175) $PN DV65
J 2
(-5035 1185);
DISPLAY 0.617021 (-5035 1185);
PAINT ORANGE (-5035 1185);
FORCEPROP 2 LASTPIN (-5025 1125) $PN EA68
J 2
(-5035 1135);
DISPLAY 0.617021 (-5035 1135);
PAINT ORANGE (-5035 1135);
FORCEPROP 2 LASTPIN (-5025 1075) $PN DY69
J 2
(-5035 1085);
DISPLAY 0.617021 (-5035 1085);
PAINT ORANGE (-5035 1085);
FORCEPROP 2 LASTPIN (-3325 4675) $PN DT67
J 0
(-3315 4685);
DISPLAY 0.617021 (-3315 4685);
PAINT ORANGE (-3315 4685);
FORCEPROP 2 LASTPIN (-3325 4625) $PN DE26
J 0
(-3315 4635);
DISPLAY 0.617021 (-3315 4635);
PAINT ORANGE (-3315 4635);
FORCEPROP 2 LASTPIN (-3325 4575) $PN DW26
J 0
(-3315 4585);
DISPLAY 0.617021 (-3315 4585);
PAINT ORANGE (-3315 4585);
FORCEPROP 2 LASTPIN (-3325 4525) $PN DW32
J 0
(-3315 4535);
DISPLAY 0.617021 (-3315 4535);
PAINT ORANGE (-3315 4535);
FORCEPROP 2 LASTPIN (-3325 4475) $PN DM41
J 0
(-3315 4485);
DISPLAY 0.617021 (-3315 4485);
PAINT ORANGE (-3315 4485);
FORCEPROP 2 LASTPIN (-3325 4425) $PN DY73
J 0
(-3315 4435);
DISPLAY 0.617021 (-3315 4435);
PAINT ORANGE (-3315 4435);
FORCEPROP 2 LASTPIN (-3325 4375) $PN DV79
J 0
(-3315 4385);
DISPLAY 0.617021 (-3315 4385);
PAINT ORANGE (-3315 4385);
FORCEPROP 2 LASTPIN (-3325 4325) $PN DD79
J 0
(-3315 4335);
DISPLAY 0.617021 (-3315 4335);
PAINT ORANGE (-3315 4335);
FORCEPROP 2 LASTPIN (-3325 4275) $PN CP79
J 0
(-3315 4285);
DISPLAY 0.617021 (-3315 4285);
PAINT ORANGE (-3315 4285);
FORCEPROP 2 LASTPIN (-3325 4225) $PN DY67
J 0
(-3315 4235);
DISPLAY 0.617021 (-3315 4235);
PAINT ORANGE (-3315 4235);
FORCEPROP 2 LASTPIN (-3325 4175) $PN DJ26
J 0
(-3315 4185);
DISPLAY 0.617021 (-3315 4185);
PAINT ORANGE (-3315 4185);
FORCEPROP 2 LASTPIN (-3325 4125) $PN EC26
J 0
(-3315 4135);
DISPLAY 0.617021 (-3315 4135);
PAINT ORANGE (-3315 4135);
FORCEPROP 2 LASTPIN (-3325 4075) $PN EC32
J 0
(-3315 4085);
DISPLAY 0.617021 (-3315 4085);
PAINT ORANGE (-3315 4085);
FORCEPROP 2 LASTPIN (-3325 4025) $PN DT41
J 0
(-3315 4035);
DISPLAY 0.617021 (-3315 4035);
PAINT ORANGE (-3315 4035);
FORCEPROP 2 LASTPIN (-3325 3975) $PN ED73
J 0
(-3315 3985);
DISPLAY 0.617021 (-3315 3985);
PAINT ORANGE (-3315 3985);
FORCEPROP 2 LASTPIN (-3325 3925) $PN EB79
J 0
(-3315 3935);
DISPLAY 0.617021 (-3315 3935);
PAINT ORANGE (-3315 3935);
FORCEPROP 2 LASTPIN (-3325 3875) $PN DB81
J 0
(-3315 3885);
DISPLAY 0.617021 (-3315 3885);
PAINT ORANGE (-3315 3885);
FORCEPROP 2 LASTPIN (-3325 3825) $PN CM81
J 0
(-3315 3835);
DISPLAY 0.617021 (-3315 3835);
PAINT ORANGE (-3315 3835);
FORCEPROP 2 LASTPIN (-3325 3725) $PN DV67
J 0
(-3315 3735);
DISPLAY 0.617021 (-3315 3735);
PAINT ORANGE (-3315 3735);
FORCEPROP 2 LASTPIN (-3325 3675) $PN DG26
J 0
(-3315 3685);
DISPLAY 0.617021 (-3315 3685);
PAINT ORANGE (-3315 3685);
FORCEPROP 2 LASTPIN (-3325 3625) $PN EA26
J 0
(-3315 3635);
DISPLAY 0.617021 (-3315 3635);
PAINT ORANGE (-3315 3635);
FORCEPROP 2 LASTPIN (-3325 3575) $PN EA32
J 0
(-3315 3585);
DISPLAY 0.617021 (-3315 3585);
PAINT ORANGE (-3315 3585);
FORCEPROP 2 LASTPIN (-3325 3525) $PN DP41
J 0
(-3315 3535);
DISPLAY 0.617021 (-3315 3535);
PAINT ORANGE (-3315 3535);
FORCEPROP 2 LASTPIN (-3325 3475) $PN EB73
J 0
(-3315 3485);
DISPLAY 0.617021 (-3315 3485);
PAINT ORANGE (-3315 3485);
FORCEPROP 2 LASTPIN (-3325 3425) $PN DY79
J 0
(-3315 3435);
DISPLAY 0.617021 (-3315 3435);
PAINT ORANGE (-3315 3435);
FORCEPROP 2 LASTPIN (-3325 3375) $PN DC80
J 0
(-3315 3385);
DISPLAY 0.617021 (-3315 3385);
PAINT ORANGE (-3315 3385);
FORCEPROP 2 LASTPIN (-3325 3325) $PN CN80
J 0
(-3315 3335);
DISPLAY 0.617021 (-3315 3335);
PAINT ORANGE (-3315 3335);
FORCEPROP 2 LASTPIN (-3325 3275) $PN EB67
J 0
(-3315 3285);
DISPLAY 0.617021 (-3315 3285);
PAINT ORANGE (-3315 3285);
FORCEPROP 2 LASTPIN (-3325 3225) $PN DL26
J 0
(-3315 3235);
DISPLAY 0.617021 (-3315 3235);
PAINT ORANGE (-3315 3235);
FORCEPROP 2 LASTPIN (-3325 3175) $PN EE26
J 0
(-3315 3185);
DISPLAY 0.617021 (-3315 3185);
PAINT ORANGE (-3315 3185);
FORCEPROP 2 LASTPIN (-3325 3125) $PN EE32
J 0
(-3315 3135);
DISPLAY 0.617021 (-3315 3135);
PAINT ORANGE (-3315 3135);
FORCEPROP 2 LASTPIN (-3325 3075) $PN DV41
J 0
(-3315 3085);
DISPLAY 0.617021 (-3315 3085);
PAINT ORANGE (-3315 3085);
FORCEPROP 2 LASTPIN (-3325 3025) $PN EF73
J 0
(-3315 3035);
DISPLAY 0.617021 (-3315 3035);
PAINT ORANGE (-3315 3035);
FORCEPROP 2 LASTPIN (-3325 2975) $PN ED79
J 0
(-3315 2985);
DISPLAY 0.617021 (-3315 2985);
PAINT ORANGE (-3315 2985);
FORCEPROP 2 LASTPIN (-3325 2925) $PN DA82
J 0
(-3315 2935);
DISPLAY 0.617021 (-3315 2935);
PAINT ORANGE (-3315 2935);
FORCEPROP 2 LASTPIN (-3325 2875) $PN CL82
J 0
(-3315 2885);
DISPLAY 0.617021 (-3315 2885);
PAINT ORANGE (-3315 2885);
FORCEPROP 2 LASTPIN (-5025 4675) $PN DK25
J 2
(-5035 4685);
DISPLAY 0.617021 (-5035 4685);
PAINT ORANGE (-5035 4685);
FORCEPROP 2 LASTPIN (-5025 4625) $PN DF25
J 2
(-5035 4635);
DISPLAY 0.617021 (-5035 4635);
PAINT ORANGE (-5035 4635);
FORCEPROP 2 LASTPIN (-5025 4575) $PN DJ28
J 2
(-5035 4585);
DISPLAY 0.617021 (-5035 4585);
PAINT ORANGE (-5035 4585);
FORCEPROP 2 LASTPIN (-5025 4525) $PN DG28
J 2
(-5035 4535);
DISPLAY 0.617021 (-5035 4535);
PAINT ORANGE (-5035 4535);
FORCEPROP 2 LASTPIN (-5025 4475) $PN DJ24
J 2
(-5035 4485);
DISPLAY 0.617021 (-5035 4485);
PAINT ORANGE (-5035 4485);
FORCEPROP 2 LASTPIN (-5025 4425) $PN DD25
J 2
(-5035 4435);
DISPLAY 0.617021 (-5035 4435);
PAINT ORANGE (-5035 4435);
FORCEPROP 2 LASTPIN (-5025 4375) $PN DK27
J 2
(-5035 4385);
DISPLAY 0.617021 (-5035 4385);
PAINT ORANGE (-5035 4385);
FORCEPROP 2 LASTPIN (-5025 4325) $PN DF27
J 2
(-5035 4335);
DISPLAY 0.617021 (-5035 4335);
PAINT ORANGE (-5035 4335);
FORCEPROP 2 LASTPIN (-5025 4275) $PN ED25
J 2
(-5035 4285);
DISPLAY 0.617021 (-5035 4285);
PAINT ORANGE (-5035 4285);
FORCEPROP 2 LASTPIN (-5025 4225) $PN DY25
J 2
(-5035 4235);
DISPLAY 0.617021 (-5035 4235);
PAINT ORANGE (-5035 4235);
FORCEPROP 2 LASTPIN (-5025 4175) $PN EA28
J 2
(-5035 4185);
DISPLAY 0.617021 (-5035 4185);
PAINT ORANGE (-5035 4185);
FORCEPROP 2 LASTPIN (-5025 4125) $PN DY27
J 2
(-5035 4135);
DISPLAY 0.617021 (-5035 4135);
PAINT ORANGE (-5035 4135);
FORCEPROP 2 LASTPIN (-5025 4075) $PN EC24
J 2
(-5035 4085);
DISPLAY 0.617021 (-5035 4085);
PAINT ORANGE (-5035 4085);
FORCEPROP 2 LASTPIN (-5025 4025) $PN EA24
J 2
(-5035 4035);
DISPLAY 0.617021 (-5035 4035);
PAINT ORANGE (-5035 4035);
FORCEPROP 2 LASTPIN (-5025 3975) $PN ED27
J 2
(-5035 3985);
DISPLAY 0.617021 (-5035 3985);
PAINT ORANGE (-5035 3985);
FORCEPROP 2 LASTPIN (-5025 3925) $PN EC28
J 2
(-5035 3935);
DISPLAY 0.617021 (-5035 3935);
PAINT ORANGE (-5035 3935);
FORCEPROP 2 LASTPIN (-5025 3875) $PN ED31
J 2
(-5035 3885);
DISPLAY 0.617021 (-5035 3885);
PAINT ORANGE (-5035 3885);
FORCEPROP 2 LASTPIN (-5025 3825) $PN DY31
J 2
(-5035 3835);
DISPLAY 0.617021 (-5035 3835);
PAINT ORANGE (-5035 3835);
FORCEPROP 2 LASTPIN (-5025 3775) $PN EA34
J 2
(-5035 3785);
DISPLAY 0.617021 (-5035 3785);
PAINT ORANGE (-5035 3785);
FORCEPROP 2 LASTPIN (-5025 3725) $PN DY33
J 2
(-5035 3735);
DISPLAY 0.617021 (-5035 3735);
PAINT ORANGE (-5035 3735);
FORCEPROP 2 LASTPIN (-5025 3675) $PN EC30
J 2
(-5035 3685);
DISPLAY 0.617021 (-5035 3685);
PAINT ORANGE (-5035 3685);
FORCEPROP 2 LASTPIN (-5025 3625) $PN EA30
J 2
(-5035 3635);
DISPLAY 0.617021 (-5035 3635);
PAINT ORANGE (-5035 3635);
FORCEPROP 2 LASTPIN (-5025 3575) $PN ED33
J 2
(-5035 3585);
DISPLAY 0.617021 (-5035 3585);
PAINT ORANGE (-5035 3585);
FORCEPROP 2 LASTPIN (-5025 3525) $PN EC34
J 2
(-5035 3535);
DISPLAY 0.617021 (-5035 3535);
PAINT ORANGE (-5035 3535);
FORCEPROP 2 LASTPIN (-5025 3475) $PN DU40
J 2
(-5035 3485);
DISPLAY 0.617021 (-5035 3485);
PAINT ORANGE (-5035 3485);
FORCEPROP 2 LASTPIN (-5025 3425) $PN DN40
J 2
(-5035 3435);
DISPLAY 0.617021 (-5035 3435);
PAINT ORANGE (-5035 3435);
FORCEPROP 2 LASTPIN (-5025 3375) $PN DN42
J 2
(-5035 3385);
DISPLAY 0.617021 (-5035 3385);
PAINT ORANGE (-5035 3385);
FORCEPROP 2 LASTPIN (-5025 3325) $PN DL42
J 2
(-5035 3335);
DISPLAY 0.617021 (-5035 3335);
PAINT ORANGE (-5035 3335);
FORCEPROP 2 LASTPIN (-5025 3275) $PN DT39
J 2
(-5035 3285);
DISPLAY 0.617021 (-5035 3285);
PAINT ORANGE (-5035 3285);
FORCEPROP 2 LASTPIN (-5025 3225) $PN DP39
J 2
(-5035 3235);
DISPLAY 0.617021 (-5035 3235);
PAINT ORANGE (-5035 3235);
FORCEPROP 2 LASTPIN (-5025 3175) $PN DW42
J 2
(-5035 3185);
DISPLAY 0.617021 (-5035 3185);
PAINT ORANGE (-5035 3185);
FORCEPROP 2 LASTPIN (-5025 3125) $PN DU42
J 2
(-5035 3135);
DISPLAY 0.617021 (-5035 3135);
PAINT ORANGE (-5035 3135);
FORCEPROP 2 LASTPIN (-5025 3075) $PN EE72
J 2
(-5035 3085);
DISPLAY 0.617021 (-5035 3085);
PAINT ORANGE (-5035 3085);
FORCEPROP 2 LASTPIN (-5025 3025) $PN EA72
J 2
(-5035 3035);
DISPLAY 0.617021 (-5035 3035);
PAINT ORANGE (-5035 3035);
FORCEPROP 2 LASTPIN (-5025 2975) $PN EB75
J 2
(-5035 2985);
DISPLAY 0.617021 (-5035 2985);
PAINT ORANGE (-5035 2985);
FORCEPROP 2 LASTPIN (-5025 2825) $PN EB71
J 2
(-5035 2835);
DISPLAY 0.617021 (-5035 2835);
PAINT ORANGE (-5035 2835);
FORCEPROP 2 LASTPIN (-5025 2775) $PN EE74
J 2
(-5035 2785);
DISPLAY 0.617021 (-5035 2785);
PAINT ORANGE (-5035 2785);
FORCEPROP 2 LASTPIN (-5025 2725) $PN ED75
J 2
(-5035 2735);
DISPLAY 0.617021 (-5035 2735);
PAINT ORANGE (-5035 2735);
FORCEPROP 2 LASTPIN (-5025 2675) $PN EC78
J 2
(-5035 2685);
DISPLAY 0.617021 (-5035 2685);
PAINT ORANGE (-5035 2685);
FORCEPROP 2 LASTPIN (-5025 2625) $PN DW78
J 2
(-5035 2635);
DISPLAY 0.617021 (-5035 2635);
PAINT ORANGE (-5035 2635);
FORCEPROP 2 LASTPIN (-5025 2575) $PN EB81
J 2
(-5035 2585);
DISPLAY 0.617021 (-5035 2585);
PAINT ORANGE (-5035 2585);
FORCEPROP 2 LASTPIN (-5025 2525) $PN DY81
J 2
(-5035 2535);
DISPLAY 0.617021 (-5035 2535);
PAINT ORANGE (-5035 2535);
FORCEPROP 2 LASTPIN (-5025 2475) $PN EB77
J 2
(-5035 2485);
DISPLAY 0.617021 (-5035 2485);
PAINT ORANGE (-5035 2485);
FORCEPROP 2 LASTPIN (-5025 2425) $PN DY77
J 2
(-5035 2435);
DISPLAY 0.617021 (-5035 2435);
PAINT ORANGE (-5035 2435);
FORCEPROP 2 LASTPIN (-5025 2375) $PN EC80
J 2
(-5035 2385);
DISPLAY 0.617021 (-5035 2385);
PAINT ORANGE (-5035 2385);
FORCEPROP 2 LASTPIN (-5025 2325) $PN DW80
J 2
(-5035 2335);
DISPLAY 0.617021 (-5035 2335);
PAINT ORANGE (-5035 2335);
FORCEPROP 2 LASTPIN (-5025 2275) $PN DE82
J 2
(-5035 2285);
DISPLAY 0.617021 (-5035 2285);
PAINT ORANGE (-5035 2285);
FORCEPROP 2 LASTPIN (-5025 2225) $PN DC82
J 2
(-5035 2235);
DISPLAY 0.617021 (-5035 2235);
PAINT ORANGE (-5035 2235);
FORCEPROP 2 LASTPIN (-5025 2175) $PN CW80
J 2
(-5035 2185);
DISPLAY 0.617021 (-5035 2185);
PAINT ORANGE (-5035 2185);
FORCEPROP 2 LASTPIN (-5025 2125) $PN CY79
J 2
(-5035 2135);
DISPLAY 0.617021 (-5035 2135);
PAINT ORANGE (-5035 2135);
FORCEPROP 2 LASTPIN (-5025 2075) $PN DF81
J 2
(-5035 2085);
DISPLAY 0.617021 (-5035 2085);
PAINT ORANGE (-5035 2085);
FORCEPROP 2 LASTPIN (-5025 2025) $PN DE80
J 2
(-5035 2035);
DISPLAY 0.617021 (-5035 2035);
PAINT ORANGE (-5035 2035);
FORCEPROP 2 LASTPIN (-5025 1975) $PN CY81
J 2
(-5035 1985);
DISPLAY 0.617021 (-5035 1985);
PAINT ORANGE (-5035 1985);
FORCEPROP 2 LASTPIN (-5025 1925) $PN DB79
J 2
(-5035 1935);
DISPLAY 0.617021 (-5035 1935);
PAINT ORANGE (-5035 1935);
FORCEPROP 2 LASTPIN (-5025 1875) $PN CN82
J 2
(-5035 1885);
DISPLAY 0.617021 (-5035 1885);
PAINT ORANGE (-5035 1885);
FORCEPROP 2 LASTPIN (-5025 1825) $PN CR80
J 2
(-5035 1835);
DISPLAY 0.617021 (-5035 1835);
PAINT ORANGE (-5035 1835);
FORCEPROP 2 LASTPIN (-5025 1775) $PN CJ80
J 2
(-5035 1785);
DISPLAY 0.617021 (-5035 1785);
PAINT ORANGE (-5035 1785);
FORCEPROP 2 LASTPIN (-5025 1725) $PN CK79
J 2
(-5035 1735);
DISPLAY 0.617021 (-5035 1735);
PAINT ORANGE (-5035 1735);
FORCEPROP 2 LASTPIN (-5025 1675) $PN CR82
J 2
(-5035 1685);
DISPLAY 0.617021 (-5035 1685);
PAINT ORANGE (-5035 1685);
FORCEPROP 2 LASTPIN (-5025 1625) $PN CT81
J 2
(-5035 1635);
DISPLAY 0.617021 (-5035 1635);
PAINT ORANGE (-5035 1635);
FORCEPROP 2 LASTPIN (-5025 1575) $PN CK81
J 2
(-5035 1585);
DISPLAY 0.617021 (-5035 1585);
PAINT ORANGE (-5035 1585);
FORCEPROP 2 LASTPIN (-5025 1525) $PN CM79
J 2
(-5035 1535);
DISPLAY 0.617021 (-5035 1535);
PAINT ORANGE (-5035 1535);
FORCEPROP 2 LASTPIN (-3325 1325) $PN DN46
J 0
(-3315 1335);
DISPLAY 0.617021 (-3315 1335);
PAINT ORANGE (-3315 1335);
FORCEPROP 2 LASTPIN (-3325 1275) $PN DT45
J 0
(-3315 1285);
DISPLAY 0.617021 (-3315 1285);
PAINT ORANGE (-3315 1285);
FORCEPROP 2 LASTPIN (-3325 1225) $PN DM49
J 0
(-3315 1235);
DISPLAY 0.617021 (-3315 1235);
PAINT ORANGE (-3315 1235);
FORCEPROP 2 LASTPIN (-3325 1175) $PN DW50
J 0
(-3315 1185);
DISPLAY 0.617021 (-3315 1185);
PAINT ORANGE (-3315 1185);
FORCEPROP 2 LASTPIN (-3325 1125) $PN DK47
J 0
(-3315 1135);
DISPLAY 0.617021 (-3315 1135);
PAINT ORANGE (-3315 1135);
FORCEPROP 2 LASTPIN (-3325 1075) $PN DR46
J 0
(-3315 1085);
DISPLAY 0.617021 (-3315 1085);
PAINT ORANGE (-3315 1085);
FORCEPROP 2 LASTPIN (-3325 1025) $PN DN50
J 0
(-3315 1035);
DISPLAY 0.617021 (-3315 1035);
PAINT ORANGE (-3315 1035);
FORCEPROP 2 LASTPIN (-3325 975) $PN DV51
J 0
(-3315 985);
DISPLAY 0.617021 (-3315 985);
PAINT ORANGE (-3315 985);
FORCEPROP 2 LASTPIN (-5025 975) $PN DR56
J 2
(-5035 985);
DISPLAY 0.617021 (-5035 985);
PAINT ORANGE (-5035 985);
FORCEPROP 2 LASTPIN (-5025 925) $PN DN56
J 2
(-5035 935);
DISPLAY 0.617021 (-5035 935);
PAINT ORANGE (-5035 935);
FORCEPROP 2 LASTPIN (-5025 875) $PN DT53
J 2
(-5035 885);
DISPLAY 0.617021 (-5035 885);
PAINT ORANGE (-5035 885);
FORCEPROP 2 LASTPIN (-5025 825) $PN DN54
J 2
(-5035 835);
DISPLAY 0.617021 (-5035 835);
PAINT ORANGE (-5035 835);
FORCEPROP 2 LASTPIN (-5025 775) $PN DT57
J 2
(-5035 785);
DISPLAY 0.617021 (-5035 785);
PAINT ORANGE (-5035 785);
FORCEPROP 2 LASTPIN (-5025 725) $PN DM57
J 2
(-5035 735);
DISPLAY 0.617021 (-5035 735);
PAINT ORANGE (-5035 735);
FORCEPROP 2 LASTPIN (-5025 675) $PN DR54
J 2
(-5035 685);
DISPLAY 0.617021 (-5035 685);
PAINT ORANGE (-5035 685);
FORCEPROP 2 LASTPIN (-5025 625) $PN DM55
J 2
(-5035 635);
DISPLAY 0.617021 (-5035 635);
PAINT ORANGE (-5035 635);
FORCEPROP 2 LASTPIN (-3325 1825) $PN DR64
J 0
(-3315 1835);
DISPLAY 0.617021 (-3315 1835);
PAINT ORANGE (-3315 1835);
FORCEPROP 2 LASTPIN (-3325 1775) $PN DL64
J 0
(-3315 1785);
DISPLAY 0.617021 (-3315 1785);
PAINT ORANGE (-3315 1785);
FORCEPROP 2 LASTPIN (-3325 1725) $PN DN64
J 0
(-3315 1735);
DISPLAY 0.617021 (-3315 1735);
PAINT ORANGE (-3315 1735);
FORCEPROP 2 LASTPIN (-3325 1675) $PN DM63
J 0
(-3315 1685);
DISPLAY 0.617021 (-3315 1685);
PAINT ORANGE (-3315 1685);
FORCEPROP 2 LASTPIN (-5025 525) $PN DT47
J 2
(-5035 535);
DISPLAY 0.617021 (-5035 535);
PAINT ORANGE (-5035 535);
FORCEPROP 2 LASTPIN (-3325 875) $PN DM61
J 0
(-3315 885);
DISPLAY 0.617021 (-3315 885);
PAINT ORANGE (-3315 885);
FORCEPROP 2 LASTPIN (-3325 825) $PN DJ62
J 0
(-3315 835);
DISPLAY 0.617021 (-3315 835);
PAINT ORANGE (-3315 835);
FORCEPROP 2 LASTPIN (-3325 775) $PN DV55
J 0
(-3315 785);
DISPLAY 0.617021 (-3315 785);
PAINT ORANGE (-3315 785);
FORCEPROP 2 LASTPIN (-3325 725) $PN DM53
J 0
(-3315 735);
DISPLAY 0.617021 (-3315 735);
PAINT ORANGE (-3315 735);
FORCEPROP 2 LASTPIN (-3325 575) $PN DT61
J 0
(-3315 585);
DISPLAY 0.617021 (-3315 585);
PAINT ORANGE (-3315 585);
FORCEPROP 2 LASTPIN (-3325 625) $PN DR62
J 0
(-3315 635);
DISPLAY 0.617021 (-3315 635);
PAINT ORANGE (-3315 635);
FORCEPROP 2 LASTPIN (-5025 2925) $PN EA74
J 2
(-5035 2935);
DISPLAY 0.617021 (-5035 2935);
PAINT ORANGE (-5035 2935);
FORCEPROP 2 LASTPIN (-5025 2875) $PN ED71
J 2
(-5035 2885);
DISPLAY 0.617021 (-5035 2885);
PAINT ORANGE (-5035 2885);
FORCEPROP 1 LAST PACK_TYPE BGA1
J 0
(-4975 4975);
PAINT SKYBLUE (-4975 4975);
DISPLAY INVISIBLE (-4975 4975);
FORCEPROP 2 LAST SEC_TYPE BGA1
J 0
(-4975 4975);
DISPLAY 1.021277 (-4975 4975);
PAINT ORANGE (-4975 4975);
DISPLAY INVISIBLE (-4975 4975);
FORCEPROP 2 LAST CDS_LIB chpset_lib
J 0
(-4175 2575);
PAINT ORANGE (-4175 2575);
DISPLAY INVISIBLE (-4175 2575);
FORCEPROP 2 LAST SEC 7
J 0
(-4975 4975);
DISPLAY 0.680851 (-4975 4975);
PAINT MONO (-4975 4975);
DISPLAY INVISIBLE (-4975 4975);
FORCEPROP 2 LAST CDS_LOCATION U2D1
J 0
(-4975 4925);
DISPLAY 0.617021 (-4975 4925);
PAINT AQUA (-4975 4925);
DISPLAY INVISIBLE (-4975 4925);
FORCEPROP 1 LAST PATH I172
J 0
(-4175 4875);
PAINT GREEN (-4175 4875);
DISPLAY INVISIBLE (-4175 4875);
FORCEADD TAP..6
(-5575 1325);
FORCEPROP 3 LASTPIN (-5525 1325) SIG_NAME M_L_ECC<5>
J 0
(-5515 1335);
DISPLAY 0.659574 (-5515 1335);
PAINT MONO (-5515 1335);
DISPLAY INVISIBLE (-5515 1335);
FORCEPROP 1 LASTPIN (-5525 1325) BN 5
J 0
(-5577 1333);
DISPLAY 0.617021 (-5577 1333);
PAINT GREEN (-5577 1333);
FORCEPROP 2 LAST CDS_LIB mstr_standard
J 0
(-5575 1325);
PAINT MONO (-5575 1325);
DISPLAY INVISIBLE (-5575 1325);
FORCEPROP 1 LAST BODY_TYPE PLUMBING
J 0
(-5575 1275);
DISPLAY 1.595745 (-5575 1275);
PAINT GREEN (-5575 1275);
DISPLAY INVISIBLE (-5575 1275);
FORCEPROP 1 LAST HDL_TAP TRUE
J 0
(-5250 1200);
DISPLAY 1.595745 (-5250 1200);
PAINT GREEN (-5250 1200);
DISPLAY INVISIBLE (-5250 1200);
FORCEPROP 1 LAST PATH I18
J 0
(-5577 1325);
DISPLAY 0.872340 (-5577 1325);
PAINT GREEN (-5577 1325);
DISPLAY INVISIBLE (-5577 1325);
FORCEADD TAP..6
(-5575 1375);
FORCEPROP 3 LASTPIN (-5525 1375) SIG_NAME M_L_ECC<6>
J 0
(-5515 1385);
DISPLAY 0.659574 (-5515 1385);
PAINT MONO (-5515 1385);
DISPLAY INVISIBLE (-5515 1385);
FORCEPROP 1 LASTPIN (-5525 1375) BN 6
J 0
(-5577 1383);
DISPLAY 0.617021 (-5577 1383);
PAINT GREEN (-5577 1383);
FORCEPROP 2 LAST CDS_LIB mstr_standard
J 0
(-5575 1375);
PAINT MONO (-5575 1375);
DISPLAY INVISIBLE (-5575 1375);
FORCEPROP 1 LAST BODY_TYPE PLUMBING
J 0
(-5575 1325);
DISPLAY 1.595745 (-5575 1325);
PAINT GREEN (-5575 1325);
DISPLAY INVISIBLE (-5575 1325);
FORCEPROP 1 LAST HDL_TAP TRUE
J 0
(-5250 1250);
DISPLAY 1.595745 (-5250 1250);
PAINT GREEN (-5250 1250);
DISPLAY INVISIBLE (-5250 1250);
FORCEPROP 1 LAST PATH I19
J 0
(-5577 1375);
DISPLAY 0.872340 (-5577 1375);
PAINT GREEN (-5577 1375);
DISPLAY INVISIBLE (-5577 1375);
FORCEADD OFFPAGE..5
(-6425 825);
FORCEPROP 2 LAST $XR1 86 
J 0
(-6769 825);
DISPLAY 0.638298 (-6769 825);
PAINT MONO (-6769 825);
FORCEPROP 2 LAST $XR0 85 
J 0
(-6679 825);
DISPLAY 0.638298 (-6679 825);
PAINT MONO (-6679 825);
FORCEPROP 2 LAST CDS_LIB mstr_standard
J 0
(-6425 825);
PAINT MONO (-6425 825);
DISPLAY INVISIBLE (-6425 825);
FORCEPROP 1 LAST OFFPAGE TRUE
J 0
(-6100 700);
DISPLAY 1.170213 (-6100 700);
PAINT GREEN (-6100 700);
DISPLAY INVISIBLE (-6100 700);
FORCEPROP 1 LAST COMMENT_BODY TRUE
J 0
(-6325 750);
DISPLAY 1.170213 (-6325 750);
PAINT GREEN (-6325 750);
DISPLAY INVISIBLE (-6325 750);
FORCEPROP 2 LAST PATH I2
J 0
(-6375 900);
DISPLAY 1.021277 (-6375 900);
PAINT ORANGE (-6375 900);
DISPLAY INVISIBLE (-6375 900);
FORCEADD TAP..6
(-5575 1425);
FORCEPROP 3 LASTPIN (-5525 1425) SIG_NAME M_L_ECC<7>
J 0
(-5515 1435);
DISPLAY 0.659574 (-5515 1435);
PAINT MONO (-5515 1435);
DISPLAY INVISIBLE (-5515 1435);
FORCEPROP 1 LASTPIN (-5525 1425) BN 7
J 0
(-5577 1433);
DISPLAY 0.617021 (-5577 1433);
PAINT GREEN (-5577 1433);
FORCEPROP 2 LAST CDS_LIB mstr_standard
J 0
(-5575 1425);
PAINT MONO (-5575 1425);
DISPLAY INVISIBLE (-5575 1425);
FORCEPROP 1 LAST BODY_TYPE PLUMBING
J 0
(-5575 1375);
DISPLAY 1.595745 (-5575 1375);
PAINT GREEN (-5575 1375);
DISPLAY INVISIBLE (-5575 1375);
FORCEPROP 1 LAST HDL_TAP TRUE
J 0
(-5250 1300);
DISPLAY 1.595745 (-5250 1300);
PAINT GREEN (-5250 1300);
DISPLAY INVISIBLE (-5250 1300);
FORCEPROP 1 LAST PATH I20
J 0
(-5577 1425);
DISPLAY 0.872340 (-5577 1425);
PAINT GREEN (-5577 1425);
DISPLAY INVISIBLE (-5577 1425);
FORCEADD TAP..6
(-5575 1525);
FORCEPROP 3 LASTPIN (-5525 1525) SIG_NAME M_L_DQ<0>
J 0
(-5515 1535);
DISPLAY 0.659574 (-5515 1535);
PAINT MONO (-5515 1535);
DISPLAY INVISIBLE (-5515 1535);
FORCEPROP 1 LASTPIN (-5525 1525) BN 0
J 0
(-5577 1533);
DISPLAY 0.617021 (-5577 1533);
PAINT GREEN (-5577 1533);
FORCEPROP 2 LAST CDS_LIB mstr_standard
J 0
(-5575 1525);
PAINT MONO (-5575 1525);
DISPLAY INVISIBLE (-5575 1525);
FORCEPROP 1 LAST BODY_TYPE PLUMBING
J 0
(-5575 1475);
DISPLAY 1.595745 (-5575 1475);
PAINT GREEN (-5575 1475);
DISPLAY INVISIBLE (-5575 1475);
FORCEPROP 1 LAST HDL_TAP TRUE
J 0
(-5250 1400);
DISPLAY 1.595745 (-5250 1400);
PAINT GREEN (-5250 1400);
DISPLAY INVISIBLE (-5250 1400);
FORCEPROP 1 LAST PATH I21
J 0
(-5577 1525);
DISPLAY 0.872340 (-5577 1525);
PAINT GREEN (-5577 1525);
DISPLAY INVISIBLE (-5577 1525);
FORCEADD TAP..6
(-5575 1575);
FORCEPROP 3 LASTPIN (-5525 1575) SIG_NAME M_L_DQ<1>
J 0
(-5515 1585);
DISPLAY 0.659574 (-5515 1585);
PAINT MONO (-5515 1585);
DISPLAY INVISIBLE (-5515 1585);
FORCEPROP 1 LASTPIN (-5525 1575) BN 1
J 0
(-5577 1583);
DISPLAY 0.617021 (-5577 1583);
PAINT GREEN (-5577 1583);
FORCEPROP 2 LAST CDS_LIB mstr_standard
J 0
(-5575 1575);
PAINT MONO (-5575 1575);
DISPLAY INVISIBLE (-5575 1575);
FORCEPROP 1 LAST BODY_TYPE PLUMBING
J 0
(-5575 1525);
DISPLAY 1.595745 (-5575 1525);
PAINT GREEN (-5575 1525);
DISPLAY INVISIBLE (-5575 1525);
FORCEPROP 1 LAST HDL_TAP TRUE
J 0
(-5250 1450);
DISPLAY 1.595745 (-5250 1450);
PAINT GREEN (-5250 1450);
DISPLAY INVISIBLE (-5250 1450);
FORCEPROP 1 LAST PATH I22
J 0
(-5577 1575);
DISPLAY 0.872340 (-5577 1575);
PAINT GREEN (-5577 1575);
DISPLAY INVISIBLE (-5577 1575);
FORCEADD TAP..6
(-5575 1625);
FORCEPROP 3 LASTPIN (-5525 1625) SIG_NAME M_L_DQ<2>
J 0
(-5515 1635);
DISPLAY 0.659574 (-5515 1635);
PAINT MONO (-5515 1635);
DISPLAY INVISIBLE (-5515 1635);
FORCEPROP 1 LASTPIN (-5525 1625) BN 2
J 0
(-5577 1633);
DISPLAY 0.617021 (-5577 1633);
PAINT GREEN (-5577 1633);
FORCEPROP 2 LAST CDS_LIB mstr_standard
J 0
(-5575 1625);
PAINT MONO (-5575 1625);
DISPLAY INVISIBLE (-5575 1625);
FORCEPROP 1 LAST BODY_TYPE PLUMBING
J 0
(-5575 1575);
DISPLAY 1.595745 (-5575 1575);
PAINT GREEN (-5575 1575);
DISPLAY INVISIBLE (-5575 1575);
FORCEPROP 1 LAST HDL_TAP TRUE
J 0
(-5250 1500);
DISPLAY 1.595745 (-5250 1500);
PAINT GREEN (-5250 1500);
DISPLAY INVISIBLE (-5250 1500);
FORCEPROP 1 LAST PATH I23
J 0
(-5577 1625);
DISPLAY 0.872340 (-5577 1625);
PAINT GREEN (-5577 1625);
DISPLAY INVISIBLE (-5577 1625);
FORCEADD TAP..6
(-5575 1675);
FORCEPROP 3 LASTPIN (-5525 1675) SIG_NAME M_L_DQ<3>
J 0
(-5515 1685);
DISPLAY 0.659574 (-5515 1685);
PAINT MONO (-5515 1685);
DISPLAY INVISIBLE (-5515 1685);
FORCEPROP 1 LASTPIN (-5525 1675) BN 3
J 0
(-5577 1683);
DISPLAY 0.617021 (-5577 1683);
PAINT GREEN (-5577 1683);
FORCEPROP 2 LAST CDS_LIB mstr_standard
J 0
(-5575 1675);
PAINT MONO (-5575 1675);
DISPLAY INVISIBLE (-5575 1675);
FORCEPROP 1 LAST BODY_TYPE PLUMBING
J 0
(-5575 1625);
DISPLAY 1.595745 (-5575 1625);
PAINT GREEN (-5575 1625);
DISPLAY INVISIBLE (-5575 1625);
FORCEPROP 1 LAST HDL_TAP TRUE
J 0
(-5250 1550);
DISPLAY 1.595745 (-5250 1550);
PAINT GREEN (-5250 1550);
DISPLAY INVISIBLE (-5250 1550);
FORCEPROP 1 LAST PATH I24
J 0
(-5577 1675);
DISPLAY 0.872340 (-5577 1675);
PAINT GREEN (-5577 1675);
DISPLAY INVISIBLE (-5577 1675);
FORCEADD TAP..6
(-5575 1725);
FORCEPROP 3 LASTPIN (-5525 1725) SIG_NAME M_L_DQ<4>
J 0
(-5515 1735);
DISPLAY 0.659574 (-5515 1735);
PAINT MONO (-5515 1735);
DISPLAY INVISIBLE (-5515 1735);
FORCEPROP 1 LASTPIN (-5525 1725) BN 4
J 0
(-5577 1733);
DISPLAY 0.617021 (-5577 1733);
PAINT GREEN (-5577 1733);
FORCEPROP 2 LAST CDS_LIB mstr_standard
J 0
(-5575 1725);
PAINT MONO (-5575 1725);
DISPLAY INVISIBLE (-5575 1725);
FORCEPROP 1 LAST BODY_TYPE PLUMBING
J 0
(-5575 1675);
DISPLAY 1.595745 (-5575 1675);
PAINT GREEN (-5575 1675);
DISPLAY INVISIBLE (-5575 1675);
FORCEPROP 1 LAST HDL_TAP TRUE
J 0
(-5250 1600);
DISPLAY 1.595745 (-5250 1600);
PAINT GREEN (-5250 1600);
DISPLAY INVISIBLE (-5250 1600);
FORCEPROP 1 LAST PATH I25
J 0
(-5577 1725);
DISPLAY 0.872340 (-5577 1725);
PAINT GREEN (-5577 1725);
DISPLAY INVISIBLE (-5577 1725);
FORCEADD TAP..6
(-5575 1775);
FORCEPROP 3 LASTPIN (-5525 1775) SIG_NAME M_L_DQ<5>
J 0
(-5515 1785);
DISPLAY 0.659574 (-5515 1785);
PAINT MONO (-5515 1785);
DISPLAY INVISIBLE (-5515 1785);
FORCEPROP 1 LASTPIN (-5525 1775) BN 5
J 0
(-5577 1783);
DISPLAY 0.617021 (-5577 1783);
PAINT GREEN (-5577 1783);
FORCEPROP 2 LAST CDS_LIB mstr_standard
J 0
(-5575 1775);
PAINT MONO (-5575 1775);
DISPLAY INVISIBLE (-5575 1775);
FORCEPROP 1 LAST BODY_TYPE PLUMBING
J 0
(-5575 1725);
DISPLAY 1.595745 (-5575 1725);
PAINT GREEN (-5575 1725);
DISPLAY INVISIBLE (-5575 1725);
FORCEPROP 1 LAST HDL_TAP TRUE
J 0
(-5250 1650);
DISPLAY 1.595745 (-5250 1650);
PAINT GREEN (-5250 1650);
DISPLAY INVISIBLE (-5250 1650);
FORCEPROP 1 LAST PATH I26
J 0
(-5577 1775);
DISPLAY 0.872340 (-5577 1775);
PAINT GREEN (-5577 1775);
DISPLAY INVISIBLE (-5577 1775);
FORCEADD TAP..6
(-5575 1825);
FORCEPROP 3 LASTPIN (-5525 1825) SIG_NAME M_L_DQ<6>
J 0
(-5515 1835);
DISPLAY 0.659574 (-5515 1835);
PAINT MONO (-5515 1835);
DISPLAY INVISIBLE (-5515 1835);
FORCEPROP 1 LASTPIN (-5525 1825) BN 6
J 0
(-5577 1833);
DISPLAY 0.617021 (-5577 1833);
PAINT GREEN (-5577 1833);
FORCEPROP 2 LAST CDS_LIB mstr_standard
J 0
(-5575 1825);
PAINT MONO (-5575 1825);
DISPLAY INVISIBLE (-5575 1825);
FORCEPROP 1 LAST BODY_TYPE PLUMBING
J 0
(-5575 1775);
DISPLAY 1.595745 (-5575 1775);
PAINT GREEN (-5575 1775);
DISPLAY INVISIBLE (-5575 1775);
FORCEPROP 1 LAST HDL_TAP TRUE
J 0
(-5250 1700);
DISPLAY 1.595745 (-5250 1700);
PAINT GREEN (-5250 1700);
DISPLAY INVISIBLE (-5250 1700);
FORCEPROP 1 LAST PATH I27
J 0
(-5577 1825);
DISPLAY 0.872340 (-5577 1825);
PAINT GREEN (-5577 1825);
DISPLAY INVISIBLE (-5577 1825);
FORCEADD TAP..6
(-5575 1925);
FORCEPROP 3 LASTPIN (-5525 1925) SIG_NAME M_L_DQ<8>
J 0
(-5515 1935);
DISPLAY 0.659574 (-5515 1935);
PAINT MONO (-5515 1935);
DISPLAY INVISIBLE (-5515 1935);
FORCEPROP 1 LASTPIN (-5525 1925) BN 8
J 0
(-5577 1933);
DISPLAY 0.617021 (-5577 1933);
PAINT GREEN (-5577 1933);
FORCEPROP 2 LAST CDS_LIB mstr_standard
J 0
(-5575 1925);
PAINT MONO (-5575 1925);
DISPLAY INVISIBLE (-5575 1925);
FORCEPROP 1 LAST BODY_TYPE PLUMBING
J 0
(-5575 1875);
DISPLAY 1.595745 (-5575 1875);
PAINT GREEN (-5575 1875);
DISPLAY INVISIBLE (-5575 1875);
FORCEPROP 1 LAST HDL_TAP TRUE
J 0
(-5250 1800);
DISPLAY 1.595745 (-5250 1800);
PAINT GREEN (-5250 1800);
DISPLAY INVISIBLE (-5250 1800);
FORCEPROP 1 LAST PATH I28
J 0
(-5577 1925);
DISPLAY 0.872340 (-5577 1925);
PAINT GREEN (-5577 1925);
DISPLAY INVISIBLE (-5577 1925);
FORCEADD TAP..6
(-5575 1875);
FORCEPROP 3 LASTPIN (-5525 1875) SIG_NAME M_L_DQ<7>
J 0
(-5515 1885);
DISPLAY 0.659574 (-5515 1885);
PAINT MONO (-5515 1885);
DISPLAY INVISIBLE (-5515 1885);
FORCEPROP 1 LASTPIN (-5525 1875) BN 7
J 0
(-5577 1883);
DISPLAY 0.617021 (-5577 1883);
PAINT GREEN (-5577 1883);
FORCEPROP 2 LAST CDS_LIB mstr_standard
J 0
(-5575 1875);
PAINT MONO (-5575 1875);
DISPLAY INVISIBLE (-5575 1875);
FORCEPROP 1 LAST BODY_TYPE PLUMBING
J 0
(-5575 1825);
DISPLAY 1.595745 (-5575 1825);
PAINT GREEN (-5575 1825);
DISPLAY INVISIBLE (-5575 1825);
FORCEPROP 1 LAST HDL_TAP TRUE
J 0
(-5250 1750);
DISPLAY 1.595745 (-5250 1750);
PAINT GREEN (-5250 1750);
DISPLAY INVISIBLE (-5250 1750);
FORCEPROP 1 LAST PATH I29
J 0
(-5577 1875);
DISPLAY 0.872340 (-5577 1875);
PAINT GREEN (-5577 1875);
DISPLAY INVISIBLE (-5577 1875);
FORCEADD OFFPAGE..5
(-6425 1025);
FORCEPROP 2 LAST $XR1 86 
J 0
(-6769 1025);
DISPLAY 0.638298 (-6769 1025);
PAINT MONO (-6769 1025);
FORCEPROP 2 LAST $XR0 85 
J 0
(-6679 1025);
DISPLAY 0.638298 (-6679 1025);
PAINT MONO (-6679 1025);
FORCEPROP 2 LAST CDS_LIB mstr_standard
J 0
(-6425 1025);
PAINT MONO (-6425 1025);
DISPLAY INVISIBLE (-6425 1025);
FORCEPROP 1 LAST OFFPAGE TRUE
J 0
(-6100 900);
DISPLAY 1.170213 (-6100 900);
PAINT GREEN (-6100 900);
DISPLAY INVISIBLE (-6100 900);
FORCEPROP 1 LAST COMMENT_BODY TRUE
J 0
(-6325 950);
DISPLAY 1.170213 (-6325 950);
PAINT GREEN (-6325 950);
DISPLAY INVISIBLE (-6325 950);
FORCEPROP 2 LAST PATH I3
J 0
(-6375 1100);
DISPLAY 1.021277 (-6375 1100);
PAINT ORANGE (-6375 1100);
DISPLAY INVISIBLE (-6375 1100);
FORCEADD TAP..6
(-5575 1975);
FORCEPROP 3 LASTPIN (-5525 1975) SIG_NAME M_L_DQ<9>
J 0
(-5515 1985);
DISPLAY 0.659574 (-5515 1985);
PAINT MONO (-5515 1985);
DISPLAY INVISIBLE (-5515 1985);
FORCEPROP 1 LASTPIN (-5525 1975) BN 9
J 0
(-5577 1983);
DISPLAY 0.617021 (-5577 1983);
PAINT GREEN (-5577 1983);
FORCEPROP 2 LAST CDS_LIB mstr_standard
J 0
(-5575 1975);
PAINT MONO (-5575 1975);
DISPLAY INVISIBLE (-5575 1975);
FORCEPROP 1 LAST BODY_TYPE PLUMBING
J 0
(-5575 1925);
DISPLAY 1.595745 (-5575 1925);
PAINT GREEN (-5575 1925);
DISPLAY INVISIBLE (-5575 1925);
FORCEPROP 1 LAST HDL_TAP TRUE
J 0
(-5250 1850);
DISPLAY 1.595745 (-5250 1850);
PAINT GREEN (-5250 1850);
DISPLAY INVISIBLE (-5250 1850);
FORCEPROP 1 LAST PATH I31
J 0
(-5577 1975);
DISPLAY 0.872340 (-5577 1975);
PAINT GREEN (-5577 1975);
DISPLAY INVISIBLE (-5577 1975);
FORCEADD TAP..6
(-5575 2025);
FORCEPROP 3 LASTPIN (-5525 2025) SIG_NAME M_L_DQ<10>
J 0
(-5515 2035);
DISPLAY 0.659574 (-5515 2035);
PAINT MONO (-5515 2035);
DISPLAY INVISIBLE (-5515 2035);
FORCEPROP 1 LASTPIN (-5525 2025) BN 10
J 0
(-5577 2033);
DISPLAY 0.617021 (-5577 2033);
PAINT GREEN (-5577 2033);
FORCEPROP 2 LAST CDS_LIB mstr_standard
J 0
(-5575 2025);
PAINT MONO (-5575 2025);
DISPLAY INVISIBLE (-5575 2025);
FORCEPROP 1 LAST BODY_TYPE PLUMBING
J 0
(-5575 1975);
DISPLAY 1.595745 (-5575 1975);
PAINT GREEN (-5575 1975);
DISPLAY INVISIBLE (-5575 1975);
FORCEPROP 1 LAST HDL_TAP TRUE
J 0
(-5250 1900);
DISPLAY 1.595745 (-5250 1900);
PAINT GREEN (-5250 1900);
DISPLAY INVISIBLE (-5250 1900);
FORCEPROP 1 LAST PATH I32
J 0
(-5577 2025);
DISPLAY 0.872340 (-5577 2025);
PAINT GREEN (-5577 2025);
DISPLAY INVISIBLE (-5577 2025);
FORCEADD TAP..6
(-5575 2075);
FORCEPROP 3 LASTPIN (-5525 2075) SIG_NAME M_L_DQ<11>
J 0
(-5515 2085);
DISPLAY 0.659574 (-5515 2085);
PAINT MONO (-5515 2085);
DISPLAY INVISIBLE (-5515 2085);
FORCEPROP 1 LASTPIN (-5525 2075) BN 11
J 0
(-5577 2083);
DISPLAY 0.617021 (-5577 2083);
PAINT GREEN (-5577 2083);
FORCEPROP 2 LAST CDS_LIB mstr_standard
J 0
(-5575 2075);
PAINT MONO (-5575 2075);
DISPLAY INVISIBLE (-5575 2075);
FORCEPROP 1 LAST BODY_TYPE PLUMBING
J 0
(-5575 2025);
DISPLAY 1.595745 (-5575 2025);
PAINT GREEN (-5575 2025);
DISPLAY INVISIBLE (-5575 2025);
FORCEPROP 1 LAST HDL_TAP TRUE
J 0
(-5250 1950);
DISPLAY 1.595745 (-5250 1950);
PAINT GREEN (-5250 1950);
DISPLAY INVISIBLE (-5250 1950);
FORCEPROP 1 LAST PATH I33
J 0
(-5577 2075);
DISPLAY 0.872340 (-5577 2075);
PAINT GREEN (-5577 2075);
DISPLAY INVISIBLE (-5577 2075);
FORCEADD TAP..6
(-5575 2125);
FORCEPROP 3 LASTPIN (-5525 2125) SIG_NAME M_L_DQ<12>
J 0
(-5515 2135);
DISPLAY 0.659574 (-5515 2135);
PAINT MONO (-5515 2135);
DISPLAY INVISIBLE (-5515 2135);
FORCEPROP 1 LASTPIN (-5525 2125) BN 12
J 0
(-5577 2133);
DISPLAY 0.617021 (-5577 2133);
PAINT GREEN (-5577 2133);
FORCEPROP 2 LAST CDS_LIB mstr_standard
J 0
(-5575 2125);
PAINT MONO (-5575 2125);
DISPLAY INVISIBLE (-5575 2125);
FORCEPROP 1 LAST BODY_TYPE PLUMBING
J 0
(-5575 2075);
DISPLAY 1.595745 (-5575 2075);
PAINT GREEN (-5575 2075);
DISPLAY INVISIBLE (-5575 2075);
FORCEPROP 1 LAST HDL_TAP TRUE
J 0
(-5250 2000);
DISPLAY 1.595745 (-5250 2000);
PAINT GREEN (-5250 2000);
DISPLAY INVISIBLE (-5250 2000);
FORCEPROP 1 LAST PATH I34
J 0
(-5577 2125);
DISPLAY 0.872340 (-5577 2125);
PAINT GREEN (-5577 2125);
DISPLAY INVISIBLE (-5577 2125);
FORCEADD TAP..6
(-5575 2175);
FORCEPROP 3 LASTPIN (-5525 2175) SIG_NAME M_L_DQ<13>
J 0
(-5515 2185);
DISPLAY 0.659574 (-5515 2185);
PAINT MONO (-5515 2185);
DISPLAY INVISIBLE (-5515 2185);
FORCEPROP 1 LASTPIN (-5525 2175) BN 13
J 0
(-5577 2183);
DISPLAY 0.617021 (-5577 2183);
PAINT GREEN (-5577 2183);
FORCEPROP 2 LAST CDS_LIB mstr_standard
J 0
(-5575 2175);
PAINT MONO (-5575 2175);
DISPLAY INVISIBLE (-5575 2175);
FORCEPROP 1 LAST BODY_TYPE PLUMBING
J 0
(-5575 2125);
DISPLAY 1.595745 (-5575 2125);
PAINT GREEN (-5575 2125);
DISPLAY INVISIBLE (-5575 2125);
FORCEPROP 1 LAST HDL_TAP TRUE
J 0
(-5250 2050);
DISPLAY 1.595745 (-5250 2050);
PAINT GREEN (-5250 2050);
DISPLAY INVISIBLE (-5250 2050);
FORCEPROP 1 LAST PATH I35
J 0
(-5577 2175);
DISPLAY 0.872340 (-5577 2175);
PAINT GREEN (-5577 2175);
DISPLAY INVISIBLE (-5577 2175);
FORCEADD TAP..6
(-5575 2225);
FORCEPROP 3 LASTPIN (-5525 2225) SIG_NAME M_L_DQ<14>
J 0
(-5515 2235);
DISPLAY 0.659574 (-5515 2235);
PAINT MONO (-5515 2235);
DISPLAY INVISIBLE (-5515 2235);
FORCEPROP 1 LASTPIN (-5525 2225) BN 14
J 0
(-5577 2233);
DISPLAY 0.617021 (-5577 2233);
PAINT GREEN (-5577 2233);
FORCEPROP 2 LAST CDS_LIB mstr_standard
J 0
(-5575 2225);
PAINT MONO (-5575 2225);
DISPLAY INVISIBLE (-5575 2225);
FORCEPROP 1 LAST BODY_TYPE PLUMBING
J 0
(-5575 2175);
DISPLAY 1.595745 (-5575 2175);
PAINT GREEN (-5575 2175);
DISPLAY INVISIBLE (-5575 2175);
FORCEPROP 1 LAST HDL_TAP TRUE
J 0
(-5250 2100);
DISPLAY 1.595745 (-5250 2100);
PAINT GREEN (-5250 2100);
DISPLAY INVISIBLE (-5250 2100);
FORCEPROP 1 LAST PATH I36
J 0
(-5577 2225);
DISPLAY 0.872340 (-5577 2225);
PAINT GREEN (-5577 2225);
DISPLAY INVISIBLE (-5577 2225);
FORCEADD TAP..6
(-5575 2275);
FORCEPROP 3 LASTPIN (-5525 2275) SIG_NAME M_L_DQ<15>
J 0
(-5515 2285);
DISPLAY 0.659574 (-5515 2285);
PAINT MONO (-5515 2285);
DISPLAY INVISIBLE (-5515 2285);
FORCEPROP 1 LASTPIN (-5525 2275) BN 15
J 0
(-5577 2283);
DISPLAY 0.617021 (-5577 2283);
PAINT GREEN (-5577 2283);
FORCEPROP 2 LAST CDS_LIB mstr_standard
J 0
(-5575 2275);
PAINT MONO (-5575 2275);
DISPLAY INVISIBLE (-5575 2275);
FORCEPROP 1 LAST BODY_TYPE PLUMBING
J 0
(-5575 2225);
DISPLAY 1.595745 (-5575 2225);
PAINT GREEN (-5575 2225);
DISPLAY INVISIBLE (-5575 2225);
FORCEPROP 1 LAST HDL_TAP TRUE
J 0
(-5250 2150);
DISPLAY 1.595745 (-5250 2150);
PAINT GREEN (-5250 2150);
DISPLAY INVISIBLE (-5250 2150);
FORCEPROP 1 LAST PATH I37
J 0
(-5577 2275);
DISPLAY 0.872340 (-5577 2275);
PAINT GREEN (-5577 2275);
DISPLAY INVISIBLE (-5577 2275);
FORCEADD TAP..6
(-5575 2325);
FORCEPROP 3 LASTPIN (-5525 2325) SIG_NAME M_L_DQ<16>
J 0
(-5515 2335);
DISPLAY 0.659574 (-5515 2335);
PAINT MONO (-5515 2335);
DISPLAY INVISIBLE (-5515 2335);
FORCEPROP 1 LASTPIN (-5525 2325) BN 16
J 0
(-5577 2333);
DISPLAY 0.617021 (-5577 2333);
PAINT GREEN (-5577 2333);
FORCEPROP 2 LAST CDS_LIB mstr_standard
J 0
(-5575 2325);
PAINT MONO (-5575 2325);
DISPLAY INVISIBLE (-5575 2325);
FORCEPROP 1 LAST BODY_TYPE PLUMBING
J 0
(-5575 2275);
DISPLAY 1.595745 (-5575 2275);
PAINT GREEN (-5575 2275);
DISPLAY INVISIBLE (-5575 2275);
FORCEPROP 1 LAST HDL_TAP TRUE
J 0
(-5250 2200);
DISPLAY 1.595745 (-5250 2200);
PAINT GREEN (-5250 2200);
DISPLAY INVISIBLE (-5250 2200);
FORCEPROP 1 LAST PATH I38
J 0
(-5577 2325);
DISPLAY 0.872340 (-5577 2325);
PAINT GREEN (-5577 2325);
DISPLAY INVISIBLE (-5577 2325);
FORCEADD TAP..6
(-5575 2375);
FORCEPROP 3 LASTPIN (-5525 2375) SIG_NAME M_L_DQ<17>
J 0
(-5515 2385);
DISPLAY 0.659574 (-5515 2385);
PAINT MONO (-5515 2385);
DISPLAY INVISIBLE (-5515 2385);
FORCEPROP 1 LASTPIN (-5525 2375) BN 17
J 0
(-5577 2383);
DISPLAY 0.617021 (-5577 2383);
PAINT GREEN (-5577 2383);
FORCEPROP 2 LAST CDS_LIB mstr_standard
J 0
(-5575 2375);
PAINT MONO (-5575 2375);
DISPLAY INVISIBLE (-5575 2375);
FORCEPROP 1 LAST BODY_TYPE PLUMBING
J 0
(-5575 2325);
DISPLAY 1.595745 (-5575 2325);
PAINT GREEN (-5575 2325);
DISPLAY INVISIBLE (-5575 2325);
FORCEPROP 1 LAST HDL_TAP TRUE
J 0
(-5250 2250);
DISPLAY 1.595745 (-5250 2250);
PAINT GREEN (-5250 2250);
DISPLAY INVISIBLE (-5250 2250);
FORCEPROP 1 LAST PATH I39
J 0
(-5577 2375);
DISPLAY 0.872340 (-5577 2375);
PAINT GREEN (-5577 2375);
DISPLAY INVISIBLE (-5577 2375);
FORCEADD OFFPAGE..6
(-6425 1475);
FORCEPROP 2 LAST $XR1 86 
J 0
(-6764 1475);
DISPLAY 0.638298 (-6764 1475);
PAINT MONO (-6764 1475);
FORCEPROP 2 LAST $XR0 85 
J 0
(-6674 1475);
DISPLAY 0.638298 (-6674 1475);
PAINT MONO (-6674 1475);
FORCEPROP 2 LAST CDS_LIB mstr_standard
J 0
(-6425 1475);
PAINT MONO (-6425 1475);
DISPLAY INVISIBLE (-6425 1475);
FORCEPROP 1 LAST OFFPAGE TRUE
J 0
(-6100 1350);
DISPLAY 1.170213 (-6100 1350);
PAINT GREEN (-6100 1350);
DISPLAY INVISIBLE (-6100 1350);
FORCEPROP 1 LAST COMMENT_BODY TRUE
J 0
(-6325 1400);
DISPLAY 1.170213 (-6325 1400);
PAINT GREEN (-6325 1400);
DISPLAY INVISIBLE (-6325 1400);
FORCEPROP 2 LAST PATH I4
J 0
(-6375 1550);
DISPLAY 1.021277 (-6375 1550);
PAINT ORANGE (-6375 1550);
DISPLAY INVISIBLE (-6375 1550);
FORCEADD TAP..6
(-5575 2425);
FORCEPROP 3 LASTPIN (-5525 2425) SIG_NAME M_L_DQ<18>
J 0
(-5515 2435);
DISPLAY 0.659574 (-5515 2435);
PAINT MONO (-5515 2435);
DISPLAY INVISIBLE (-5515 2435);
FORCEPROP 1 LASTPIN (-5525 2425) BN 18
J 0
(-5577 2433);
DISPLAY 0.617021 (-5577 2433);
PAINT GREEN (-5577 2433);
FORCEPROP 2 LAST CDS_LIB mstr_standard
J 0
(-5575 2425);
PAINT MONO (-5575 2425);
DISPLAY INVISIBLE (-5575 2425);
FORCEPROP 1 LAST BODY_TYPE PLUMBING
J 0
(-5575 2375);
DISPLAY 1.595745 (-5575 2375);
PAINT GREEN (-5575 2375);
DISPLAY INVISIBLE (-5575 2375);
FORCEPROP 1 LAST HDL_TAP TRUE
J 0
(-5250 2300);
DISPLAY 1.595745 (-5250 2300);
PAINT GREEN (-5250 2300);
DISPLAY INVISIBLE (-5250 2300);
FORCEPROP 1 LAST PATH I40
J 0
(-5577 2425);
DISPLAY 0.872340 (-5577 2425);
PAINT GREEN (-5577 2425);
DISPLAY INVISIBLE (-5577 2425);
FORCEADD TAP..6
(-5575 2475);
FORCEPROP 3 LASTPIN (-5525 2475) SIG_NAME M_L_DQ<19>
J 0
(-5515 2485);
DISPLAY 0.659574 (-5515 2485);
PAINT MONO (-5515 2485);
DISPLAY INVISIBLE (-5515 2485);
FORCEPROP 1 LASTPIN (-5525 2475) BN 19
J 0
(-5577 2483);
DISPLAY 0.617021 (-5577 2483);
PAINT GREEN (-5577 2483);
FORCEPROP 2 LAST CDS_LIB mstr_standard
J 0
(-5575 2475);
PAINT MONO (-5575 2475);
DISPLAY INVISIBLE (-5575 2475);
FORCEPROP 1 LAST BODY_TYPE PLUMBING
J 0
(-5575 2425);
DISPLAY 1.595745 (-5575 2425);
PAINT GREEN (-5575 2425);
DISPLAY INVISIBLE (-5575 2425);
FORCEPROP 1 LAST HDL_TAP TRUE
J 0
(-5250 2350);
DISPLAY 1.595745 (-5250 2350);
PAINT GREEN (-5250 2350);
DISPLAY INVISIBLE (-5250 2350);
FORCEPROP 1 LAST PATH I41
J 0
(-5577 2475);
DISPLAY 0.872340 (-5577 2475);
PAINT GREEN (-5577 2475);
DISPLAY INVISIBLE (-5577 2475);
FORCEADD TAP..6
(-5575 2525);
FORCEPROP 3 LASTPIN (-5525 2525) SIG_NAME M_L_DQ<20>
J 0
(-5515 2535);
DISPLAY 0.659574 (-5515 2535);
PAINT MONO (-5515 2535);
DISPLAY INVISIBLE (-5515 2535);
FORCEPROP 1 LASTPIN (-5525 2525) BN 20
J 0
(-5577 2533);
DISPLAY 0.617021 (-5577 2533);
PAINT GREEN (-5577 2533);
FORCEPROP 2 LAST CDS_LIB mstr_standard
J 0
(-5575 2525);
PAINT MONO (-5575 2525);
DISPLAY INVISIBLE (-5575 2525);
FORCEPROP 1 LAST BODY_TYPE PLUMBING
J 0
(-5575 2475);
DISPLAY 1.595745 (-5575 2475);
PAINT GREEN (-5575 2475);
DISPLAY INVISIBLE (-5575 2475);
FORCEPROP 1 LAST HDL_TAP TRUE
J 0
(-5250 2400);
DISPLAY 1.595745 (-5250 2400);
PAINT GREEN (-5250 2400);
DISPLAY INVISIBLE (-5250 2400);
FORCEPROP 1 LAST PATH I42
J 0
(-5577 2525);
DISPLAY 0.872340 (-5577 2525);
PAINT GREEN (-5577 2525);
DISPLAY INVISIBLE (-5577 2525);
FORCEADD TAP..6
(-5575 2575);
FORCEPROP 3 LASTPIN (-5525 2575) SIG_NAME M_L_DQ<21>
J 0
(-5515 2585);
DISPLAY 0.659574 (-5515 2585);
PAINT MONO (-5515 2585);
DISPLAY INVISIBLE (-5515 2585);
FORCEPROP 1 LASTPIN (-5525 2575) BN 21
J 0
(-5577 2583);
DISPLAY 0.617021 (-5577 2583);
PAINT GREEN (-5577 2583);
FORCEPROP 2 LAST CDS_LIB mstr_standard
J 0
(-5575 2575);
PAINT MONO (-5575 2575);
DISPLAY INVISIBLE (-5575 2575);
FORCEPROP 1 LAST BODY_TYPE PLUMBING
J 0
(-5575 2525);
DISPLAY 1.595745 (-5575 2525);
PAINT GREEN (-5575 2525);
DISPLAY INVISIBLE (-5575 2525);
FORCEPROP 1 LAST HDL_TAP TRUE
J 0
(-5250 2450);
DISPLAY 1.595745 (-5250 2450);
PAINT GREEN (-5250 2450);
DISPLAY INVISIBLE (-5250 2450);
FORCEPROP 1 LAST PATH I43
J 0
(-5577 2575);
DISPLAY 0.872340 (-5577 2575);
PAINT GREEN (-5577 2575);
DISPLAY INVISIBLE (-5577 2575);
FORCEADD TAP..6
(-5575 2625);
FORCEPROP 3 LASTPIN (-5525 2625) SIG_NAME M_L_DQ<22>
J 0
(-5515 2635);
DISPLAY 0.659574 (-5515 2635);
PAINT MONO (-5515 2635);
DISPLAY INVISIBLE (-5515 2635);
FORCEPROP 1 LASTPIN (-5525 2625) BN 22
J 0
(-5577 2633);
DISPLAY 0.617021 (-5577 2633);
PAINT GREEN (-5577 2633);
FORCEPROP 2 LAST CDS_LIB mstr_standard
J 0
(-5575 2625);
PAINT MONO (-5575 2625);
DISPLAY INVISIBLE (-5575 2625);
FORCEPROP 1 LAST BODY_TYPE PLUMBING
J 0
(-5575 2575);
DISPLAY 1.595745 (-5575 2575);
PAINT GREEN (-5575 2575);
DISPLAY INVISIBLE (-5575 2575);
FORCEPROP 1 LAST HDL_TAP TRUE
J 0
(-5250 2500);
DISPLAY 1.595745 (-5250 2500);
PAINT GREEN (-5250 2500);
DISPLAY INVISIBLE (-5250 2500);
FORCEPROP 1 LAST PATH I44
J 0
(-5577 2625);
DISPLAY 0.872340 (-5577 2625);
PAINT GREEN (-5577 2625);
DISPLAY INVISIBLE (-5577 2625);
FORCEADD TAP..6
(-5575 2675);
FORCEPROP 3 LASTPIN (-5525 2675) SIG_NAME M_L_DQ<23>
J 0
(-5515 2685);
DISPLAY 0.659574 (-5515 2685);
PAINT MONO (-5515 2685);
DISPLAY INVISIBLE (-5515 2685);
FORCEPROP 1 LASTPIN (-5525 2675) BN 23
J 0
(-5577 2683);
DISPLAY 0.617021 (-5577 2683);
PAINT GREEN (-5577 2683);
FORCEPROP 2 LAST CDS_LIB mstr_standard
J 0
(-5575 2675);
PAINT MONO (-5575 2675);
DISPLAY INVISIBLE (-5575 2675);
FORCEPROP 1 LAST BODY_TYPE PLUMBING
J 0
(-5575 2625);
DISPLAY 1.595745 (-5575 2625);
PAINT GREEN (-5575 2625);
DISPLAY INVISIBLE (-5575 2625);
FORCEPROP 1 LAST HDL_TAP TRUE
J 0
(-5250 2550);
DISPLAY 1.595745 (-5250 2550);
PAINT GREEN (-5250 2550);
DISPLAY INVISIBLE (-5250 2550);
FORCEPROP 1 LAST PATH I45
J 0
(-5577 2675);
DISPLAY 0.872340 (-5577 2675);
PAINT GREEN (-5577 2675);
DISPLAY INVISIBLE (-5577 2675);
FORCEADD TAP..6
(-5575 2725);
FORCEPROP 3 LASTPIN (-5525 2725) SIG_NAME M_L_DQ<24>
J 0
(-5515 2735);
DISPLAY 0.659574 (-5515 2735);
PAINT MONO (-5515 2735);
DISPLAY INVISIBLE (-5515 2735);
FORCEPROP 1 LASTPIN (-5525 2725) BN 24
J 0
(-5577 2733);
DISPLAY 0.617021 (-5577 2733);
PAINT GREEN (-5577 2733);
FORCEPROP 2 LAST CDS_LIB mstr_standard
J 0
(-5575 2725);
PAINT MONO (-5575 2725);
DISPLAY INVISIBLE (-5575 2725);
FORCEPROP 1 LAST BODY_TYPE PLUMBING
J 0
(-5575 2675);
DISPLAY 1.595745 (-5575 2675);
PAINT GREEN (-5575 2675);
DISPLAY INVISIBLE (-5575 2675);
FORCEPROP 1 LAST HDL_TAP TRUE
J 0
(-5250 2600);
DISPLAY 1.595745 (-5250 2600);
PAINT GREEN (-5250 2600);
DISPLAY INVISIBLE (-5250 2600);
FORCEPROP 1 LAST PATH I46
J 0
(-5577 2725);
DISPLAY 0.872340 (-5577 2725);
PAINT GREEN (-5577 2725);
DISPLAY INVISIBLE (-5577 2725);
FORCEADD TAP..6
(-5575 2825);
FORCEPROP 3 LASTPIN (-5525 2825) SIG_NAME M_L_DQ<26>
J 0
(-5515 2835);
DISPLAY 0.659574 (-5515 2835);
PAINT MONO (-5515 2835);
DISPLAY INVISIBLE (-5515 2835);
FORCEPROP 1 LASTPIN (-5525 2825) BN 26
J 0
(-5577 2833);
DISPLAY 0.617021 (-5577 2833);
PAINT GREEN (-5577 2833);
FORCEPROP 2 LAST CDS_LIB mstr_standard
J 0
(-5575 2825);
PAINT MONO (-5575 2825);
DISPLAY INVISIBLE (-5575 2825);
FORCEPROP 1 LAST BODY_TYPE PLUMBING
J 0
(-5575 2775);
DISPLAY 1.595745 (-5575 2775);
PAINT GREEN (-5575 2775);
DISPLAY INVISIBLE (-5575 2775);
FORCEPROP 1 LAST HDL_TAP TRUE
J 0
(-5250 2700);
DISPLAY 1.595745 (-5250 2700);
PAINT GREEN (-5250 2700);
DISPLAY INVISIBLE (-5250 2700);
FORCEPROP 1 LAST PATH I47
J 0
(-5577 2825);
DISPLAY 0.872340 (-5577 2825);
PAINT GREEN (-5577 2825);
DISPLAY INVISIBLE (-5577 2825);
FORCEADD TAP..6
(-5575 2775);
FORCEPROP 3 LASTPIN (-5525 2775) SIG_NAME M_L_DQ<25>
J 0
(-5515 2785);
DISPLAY 0.659574 (-5515 2785);
PAINT MONO (-5515 2785);
DISPLAY INVISIBLE (-5515 2785);
FORCEPROP 1 LASTPIN (-5525 2775) BN 25
J 0
(-5577 2783);
DISPLAY 0.617021 (-5577 2783);
PAINT GREEN (-5577 2783);
FORCEPROP 2 LAST CDS_LIB mstr_standard
J 0
(-5575 2775);
PAINT MONO (-5575 2775);
DISPLAY INVISIBLE (-5575 2775);
FORCEPROP 1 LAST BODY_TYPE PLUMBING
J 0
(-5575 2725);
DISPLAY 1.595745 (-5575 2725);
PAINT GREEN (-5575 2725);
DISPLAY INVISIBLE (-5575 2725);
FORCEPROP 1 LAST HDL_TAP TRUE
J 0
(-5250 2650);
DISPLAY 1.595745 (-5250 2650);
PAINT GREEN (-5250 2650);
DISPLAY INVISIBLE (-5250 2650);
FORCEPROP 1 LAST PATH I48
J 0
(-5577 2775);
DISPLAY 0.872340 (-5577 2775);
PAINT GREEN (-5577 2775);
DISPLAY INVISIBLE (-5577 2775);
FORCEADD TAP..6
(-5575 2875);
FORCEPROP 3 LASTPIN (-5525 2875) SIG_NAME M_L_DQ<27>
J 0
(-5515 2885);
DISPLAY 0.659574 (-5515 2885);
PAINT MONO (-5515 2885);
DISPLAY INVISIBLE (-5515 2885);
FORCEPROP 1 LASTPIN (-5525 2875) BN 27
J 0
(-5577 2883);
DISPLAY 0.617021 (-5577 2883);
PAINT GREEN (-5577 2883);
FORCEPROP 2 LAST CDS_LIB mstr_standard
J 0
(-5575 2875);
PAINT MONO (-5575 2875);
DISPLAY INVISIBLE (-5575 2875);
FORCEPROP 1 LAST BODY_TYPE PLUMBING
J 0
(-5575 2825);
DISPLAY 1.595745 (-5575 2825);
PAINT GREEN (-5575 2825);
DISPLAY INVISIBLE (-5575 2825);
FORCEPROP 1 LAST HDL_TAP TRUE
J 0
(-5250 2750);
DISPLAY 1.595745 (-5250 2750);
PAINT GREEN (-5250 2750);
DISPLAY INVISIBLE (-5250 2750);
FORCEPROP 1 LAST PATH I49
J 0
(-5577 2875);
DISPLAY 0.872340 (-5577 2875);
PAINT GREEN (-5577 2875);
DISPLAY INVISIBLE (-5577 2875);
FORCEADD TAP..6
(-5575 625);
FORCEPROP 3 LASTPIN (-5525 625) SIG_NAME M_L_CLK_DN<0>
J 0
(-5515 635);
DISPLAY 0.659574 (-5515 635);
PAINT MONO (-5515 635);
DISPLAY INVISIBLE (-5515 635);
FORCEPROP 1 LASTPIN (-5525 625) BN 0
J 0
(-5577 633);
DISPLAY 0.617021 (-5577 633);
PAINT GREEN (-5577 633);
FORCEPROP 2 LAST CDS_LIB mstr_standard
J 0
(-5575 625);
PAINT MONO (-5575 625);
DISPLAY INVISIBLE (-5575 625);
FORCEPROP 1 LAST BODY_TYPE PLUMBING
J 0
(-5575 575);
DISPLAY 1.595745 (-5575 575);
PAINT GREEN (-5575 575);
DISPLAY INVISIBLE (-5575 575);
FORCEPROP 1 LAST HDL_TAP TRUE
J 0
(-5250 500);
DISPLAY 1.595745 (-5250 500);
PAINT GREEN (-5250 500);
DISPLAY INVISIBLE (-5250 500);
FORCEPROP 1 LAST PATH I5
J 0
(-5577 625);
DISPLAY 0.872340 (-5577 625);
PAINT GREEN (-5577 625);
DISPLAY INVISIBLE (-5577 625);
FORCEADD TAP..6
(-5575 2925);
FORCEPROP 3 LASTPIN (-5525 2925) SIG_NAME M_L_DQ<28>
J 0
(-5515 2935);
DISPLAY 0.659574 (-5515 2935);
PAINT MONO (-5515 2935);
DISPLAY INVISIBLE (-5515 2935);
FORCEPROP 1 LASTPIN (-5525 2925) BN 28
J 0
(-5577 2933);
DISPLAY 0.617021 (-5577 2933);
PAINT GREEN (-5577 2933);
FORCEPROP 2 LAST CDS_LIB mstr_standard
J 0
(-5575 2925);
PAINT MONO (-5575 2925);
DISPLAY INVISIBLE (-5575 2925);
FORCEPROP 1 LAST BODY_TYPE PLUMBING
J 0
(-5575 2875);
DISPLAY 1.595745 (-5575 2875);
PAINT GREEN (-5575 2875);
DISPLAY INVISIBLE (-5575 2875);
FORCEPROP 1 LAST HDL_TAP TRUE
J 0
(-5250 2800);
DISPLAY 1.595745 (-5250 2800);
PAINT GREEN (-5250 2800);
DISPLAY INVISIBLE (-5250 2800);
FORCEPROP 1 LAST PATH I50
J 0
(-5577 2925);
DISPLAY 0.872340 (-5577 2925);
PAINT GREEN (-5577 2925);
DISPLAY INVISIBLE (-5577 2925);
FORCEADD TAP..6
(-5575 2975);
FORCEPROP 3 LASTPIN (-5525 2975) SIG_NAME M_L_DQ<29>
J 0
(-5515 2985);
DISPLAY 0.659574 (-5515 2985);
PAINT MONO (-5515 2985);
DISPLAY INVISIBLE (-5515 2985);
FORCEPROP 1 LASTPIN (-5525 2975) BN 29
J 0
(-5577 2983);
DISPLAY 0.617021 (-5577 2983);
PAINT GREEN (-5577 2983);
FORCEPROP 2 LAST CDS_LIB mstr_standard
J 0
(-5575 2975);
PAINT MONO (-5575 2975);
DISPLAY INVISIBLE (-5575 2975);
FORCEPROP 1 LAST BODY_TYPE PLUMBING
J 0
(-5575 2925);
DISPLAY 1.595745 (-5575 2925);
PAINT GREEN (-5575 2925);
DISPLAY INVISIBLE (-5575 2925);
FORCEPROP 1 LAST HDL_TAP TRUE
J 0
(-5250 2850);
DISPLAY 1.595745 (-5250 2850);
PAINT GREEN (-5250 2850);
DISPLAY INVISIBLE (-5250 2850);
FORCEPROP 1 LAST PATH I51
J 0
(-5577 2975);
DISPLAY 0.872340 (-5577 2975);
PAINT GREEN (-5577 2975);
DISPLAY INVISIBLE (-5577 2975);
FORCEADD TAP..6
(-5575 3075);
FORCEPROP 3 LASTPIN (-5525 3075) SIG_NAME M_L_DQ<31>
J 0
(-5515 3085);
DISPLAY 0.659574 (-5515 3085);
PAINT MONO (-5515 3085);
DISPLAY INVISIBLE (-5515 3085);
FORCEPROP 1 LASTPIN (-5525 3075) BN 31
J 0
(-5577 3083);
DISPLAY 0.617021 (-5577 3083);
PAINT GREEN (-5577 3083);
FORCEPROP 2 LAST CDS_LIB mstr_standard
J 0
(-5575 3075);
PAINT MONO (-5575 3075);
DISPLAY INVISIBLE (-5575 3075);
FORCEPROP 1 LAST BODY_TYPE PLUMBING
J 0
(-5575 3025);
DISPLAY 1.595745 (-5575 3025);
PAINT GREEN (-5575 3025);
DISPLAY INVISIBLE (-5575 3025);
FORCEPROP 1 LAST HDL_TAP TRUE
J 0
(-5250 2950);
DISPLAY 1.595745 (-5250 2950);
PAINT GREEN (-5250 2950);
DISPLAY INVISIBLE (-5250 2950);
FORCEPROP 1 LAST PATH I52
J 0
(-5577 3075);
DISPLAY 0.872340 (-5577 3075);
PAINT GREEN (-5577 3075);
DISPLAY INVISIBLE (-5577 3075);
FORCEADD TAP..6
(-5575 3025);
FORCEPROP 3 LASTPIN (-5525 3025) SIG_NAME M_L_DQ<30>
J 0
(-5515 3035);
DISPLAY 0.659574 (-5515 3035);
PAINT MONO (-5515 3035);
DISPLAY INVISIBLE (-5515 3035);
FORCEPROP 1 LASTPIN (-5525 3025) BN 30
J 0
(-5577 3033);
DISPLAY 0.617021 (-5577 3033);
PAINT GREEN (-5577 3033);
FORCEPROP 2 LAST CDS_LIB mstr_standard
J 0
(-5575 3025);
PAINT MONO (-5575 3025);
DISPLAY INVISIBLE (-5575 3025);
FORCEPROP 1 LAST BODY_TYPE PLUMBING
J 0
(-5575 2975);
DISPLAY 1.595745 (-5575 2975);
PAINT GREEN (-5575 2975);
DISPLAY INVISIBLE (-5575 2975);
FORCEPROP 1 LAST HDL_TAP TRUE
J 0
(-5250 2900);
DISPLAY 1.595745 (-5250 2900);
PAINT GREEN (-5250 2900);
DISPLAY INVISIBLE (-5250 2900);
FORCEPROP 1 LAST PATH I53
J 0
(-5577 3025);
DISPLAY 0.872340 (-5577 3025);
PAINT GREEN (-5577 3025);
DISPLAY INVISIBLE (-5577 3025);
FORCEADD TAP..6
(-5575 3125);
FORCEPROP 3 LASTPIN (-5525 3125) SIG_NAME M_L_DQ<32>
J 0
(-5515 3135);
DISPLAY 0.659574 (-5515 3135);
PAINT MONO (-5515 3135);
DISPLAY INVISIBLE (-5515 3135);
FORCEPROP 1 LASTPIN (-5525 3125) BN 32
J 0
(-5577 3133);
DISPLAY 0.617021 (-5577 3133);
PAINT GREEN (-5577 3133);
FORCEPROP 2 LAST CDS_LIB mstr_standard
J 0
(-5575 3125);
PAINT MONO (-5575 3125);
DISPLAY INVISIBLE (-5575 3125);
FORCEPROP 1 LAST BODY_TYPE PLUMBING
J 0
(-5575 3075);
DISPLAY 1.595745 (-5575 3075);
PAINT GREEN (-5575 3075);
DISPLAY INVISIBLE (-5575 3075);
FORCEPROP 1 LAST HDL_TAP TRUE
J 0
(-5250 3000);
DISPLAY 1.595745 (-5250 3000);
PAINT GREEN (-5250 3000);
DISPLAY INVISIBLE (-5250 3000);
FORCEPROP 1 LAST PATH I54
J 0
(-5577 3125);
DISPLAY 0.872340 (-5577 3125);
PAINT GREEN (-5577 3125);
DISPLAY INVISIBLE (-5577 3125);
FORCEADD TAP..6
(-5575 3175);
FORCEPROP 3 LASTPIN (-5525 3175) SIG_NAME M_L_DQ<33>
J 0
(-5515 3185);
DISPLAY 0.659574 (-5515 3185);
PAINT MONO (-5515 3185);
DISPLAY INVISIBLE (-5515 3185);
FORCEPROP 1 LASTPIN (-5525 3175) BN 33
J 0
(-5577 3183);
DISPLAY 0.617021 (-5577 3183);
PAINT GREEN (-5577 3183);
FORCEPROP 2 LAST CDS_LIB mstr_standard
J 0
(-5575 3175);
PAINT MONO (-5575 3175);
DISPLAY INVISIBLE (-5575 3175);
FORCEPROP 1 LAST BODY_TYPE PLUMBING
J 0
(-5575 3125);
DISPLAY 1.595745 (-5575 3125);
PAINT GREEN (-5575 3125);
DISPLAY INVISIBLE (-5575 3125);
FORCEPROP 1 LAST HDL_TAP TRUE
J 0
(-5250 3050);
DISPLAY 1.595745 (-5250 3050);
PAINT GREEN (-5250 3050);
DISPLAY INVISIBLE (-5250 3050);
FORCEPROP 1 LAST PATH I55
J 0
(-5577 3175);
DISPLAY 0.872340 (-5577 3175);
PAINT GREEN (-5577 3175);
DISPLAY INVISIBLE (-5577 3175);
FORCEADD TAP..6
(-5575 3225);
FORCEPROP 3 LASTPIN (-5525 3225) SIG_NAME M_L_DQ<34>
J 0
(-5515 3235);
DISPLAY 0.659574 (-5515 3235);
PAINT MONO (-5515 3235);
DISPLAY INVISIBLE (-5515 3235);
FORCEPROP 1 LASTPIN (-5525 3225) BN 34
J 0
(-5577 3233);
DISPLAY 0.617021 (-5577 3233);
PAINT GREEN (-5577 3233);
FORCEPROP 2 LAST CDS_LIB mstr_standard
J 0
(-5575 3225);
PAINT MONO (-5575 3225);
DISPLAY INVISIBLE (-5575 3225);
FORCEPROP 1 LAST BODY_TYPE PLUMBING
J 0
(-5575 3175);
DISPLAY 1.595745 (-5575 3175);
PAINT GREEN (-5575 3175);
DISPLAY INVISIBLE (-5575 3175);
FORCEPROP 1 LAST HDL_TAP TRUE
J 0
(-5250 3100);
DISPLAY 1.595745 (-5250 3100);
PAINT GREEN (-5250 3100);
DISPLAY INVISIBLE (-5250 3100);
FORCEPROP 1 LAST PATH I56
J 0
(-5577 3225);
DISPLAY 0.872340 (-5577 3225);
PAINT GREEN (-5577 3225);
DISPLAY INVISIBLE (-5577 3225);
FORCEADD TAP..6
(-5575 3325);
FORCEPROP 3 LASTPIN (-5525 3325) SIG_NAME M_L_DQ<36>
J 0
(-5515 3335);
DISPLAY 0.659574 (-5515 3335);
PAINT MONO (-5515 3335);
DISPLAY INVISIBLE (-5515 3335);
FORCEPROP 1 LASTPIN (-5525 3325) BN 36
J 0
(-5577 3333);
DISPLAY 0.617021 (-5577 3333);
PAINT GREEN (-5577 3333);
FORCEPROP 2 LAST CDS_LIB mstr_standard
J 0
(-5575 3325);
PAINT MONO (-5575 3325);
DISPLAY INVISIBLE (-5575 3325);
FORCEPROP 1 LAST BODY_TYPE PLUMBING
J 0
(-5575 3275);
DISPLAY 1.595745 (-5575 3275);
PAINT GREEN (-5575 3275);
DISPLAY INVISIBLE (-5575 3275);
FORCEPROP 1 LAST HDL_TAP TRUE
J 0
(-5250 3200);
DISPLAY 1.595745 (-5250 3200);
PAINT GREEN (-5250 3200);
DISPLAY INVISIBLE (-5250 3200);
FORCEPROP 1 LAST PATH I57
J 0
(-5577 3325);
DISPLAY 0.872340 (-5577 3325);
PAINT GREEN (-5577 3325);
DISPLAY INVISIBLE (-5577 3325);
FORCEADD TAP..6
(-5575 3275);
FORCEPROP 3 LASTPIN (-5525 3275) SIG_NAME M_L_DQ<35>
J 0
(-5515 3285);
DISPLAY 0.659574 (-5515 3285);
PAINT MONO (-5515 3285);
DISPLAY INVISIBLE (-5515 3285);
FORCEPROP 1 LASTPIN (-5525 3275) BN 35
J 0
(-5577 3283);
DISPLAY 0.617021 (-5577 3283);
PAINT GREEN (-5577 3283);
FORCEPROP 2 LAST CDS_LIB mstr_standard
J 0
(-5575 3275);
PAINT MONO (-5575 3275);
DISPLAY INVISIBLE (-5575 3275);
FORCEPROP 1 LAST BODY_TYPE PLUMBING
J 0
(-5575 3225);
DISPLAY 1.595745 (-5575 3225);
PAINT GREEN (-5575 3225);
DISPLAY INVISIBLE (-5575 3225);
FORCEPROP 1 LAST HDL_TAP TRUE
J 0
(-5250 3150);
DISPLAY 1.595745 (-5250 3150);
PAINT GREEN (-5250 3150);
DISPLAY INVISIBLE (-5250 3150);
FORCEPROP 1 LAST PATH I58
J 0
(-5577 3275);
DISPLAY 0.872340 (-5577 3275);
PAINT GREEN (-5577 3275);
DISPLAY INVISIBLE (-5577 3275);
FORCEADD TAP..6
(-5575 3375);
FORCEPROP 3 LASTPIN (-5525 3375) SIG_NAME M_L_DQ<37>
J 0
(-5515 3385);
DISPLAY 0.659574 (-5515 3385);
PAINT MONO (-5515 3385);
DISPLAY INVISIBLE (-5515 3385);
FORCEPROP 1 LASTPIN (-5525 3375) BN 37
J 0
(-5577 3383);
DISPLAY 0.617021 (-5577 3383);
PAINT GREEN (-5577 3383);
FORCEPROP 2 LAST CDS_LIB mstr_standard
J 0
(-5575 3375);
PAINT MONO (-5575 3375);
DISPLAY INVISIBLE (-5575 3375);
FORCEPROP 1 LAST BODY_TYPE PLUMBING
J 0
(-5575 3325);
DISPLAY 1.595745 (-5575 3325);
PAINT GREEN (-5575 3325);
DISPLAY INVISIBLE (-5575 3325);
FORCEPROP 1 LAST HDL_TAP TRUE
J 0
(-5250 3250);
DISPLAY 1.595745 (-5250 3250);
PAINT GREEN (-5250 3250);
DISPLAY INVISIBLE (-5250 3250);
FORCEPROP 1 LAST PATH I59
J 0
(-5577 3375);
DISPLAY 0.872340 (-5577 3375);
PAINT GREEN (-5577 3375);
DISPLAY INVISIBLE (-5577 3375);
FORCEADD TAP..6
(-5575 675);
FORCEPROP 3 LASTPIN (-5525 675) SIG_NAME M_L_CLK_DN<1>
J 0
(-5515 685);
DISPLAY 0.659574 (-5515 685);
PAINT MONO (-5515 685);
DISPLAY INVISIBLE (-5515 685);
FORCEPROP 1 LASTPIN (-5525 675) BN 1
J 0
(-5577 683);
DISPLAY 0.617021 (-5577 683);
PAINT GREEN (-5577 683);
FORCEPROP 2 LAST CDS_LIB mstr_standard
J 0
(-5575 675);
PAINT MONO (-5575 675);
DISPLAY INVISIBLE (-5575 675);
FORCEPROP 1 LAST BODY_TYPE PLUMBING
J 0
(-5575 625);
DISPLAY 1.595745 (-5575 625);
PAINT GREEN (-5575 625);
DISPLAY INVISIBLE (-5575 625);
FORCEPROP 1 LAST HDL_TAP TRUE
J 0
(-5250 550);
DISPLAY 1.595745 (-5250 550);
PAINT GREEN (-5250 550);
DISPLAY INVISIBLE (-5250 550);
FORCEPROP 1 LAST PATH I6
J 0
(-5577 675);
DISPLAY 0.872340 (-5577 675);
PAINT GREEN (-5577 675);
DISPLAY INVISIBLE (-5577 675);
FORCEADD TAP..6
(-5575 3425);
FORCEPROP 3 LASTPIN (-5525 3425) SIG_NAME M_L_DQ<38>
J 0
(-5515 3435);
DISPLAY 0.659574 (-5515 3435);
PAINT MONO (-5515 3435);
DISPLAY INVISIBLE (-5515 3435);
FORCEPROP 1 LASTPIN (-5525 3425) BN 38
J 0
(-5577 3433);
DISPLAY 0.617021 (-5577 3433);
PAINT GREEN (-5577 3433);
FORCEPROP 2 LAST CDS_LIB mstr_standard
J 0
(-5575 3425);
PAINT MONO (-5575 3425);
DISPLAY INVISIBLE (-5575 3425);
FORCEPROP 1 LAST BODY_TYPE PLUMBING
J 0
(-5575 3375);
DISPLAY 1.595745 (-5575 3375);
PAINT GREEN (-5575 3375);
DISPLAY INVISIBLE (-5575 3375);
FORCEPROP 1 LAST HDL_TAP TRUE
J 0
(-5250 3300);
DISPLAY 1.595745 (-5250 3300);
PAINT GREEN (-5250 3300);
DISPLAY INVISIBLE (-5250 3300);
FORCEPROP 1 LAST PATH I60
J 0
(-5577 3425);
DISPLAY 0.872340 (-5577 3425);
PAINT GREEN (-5577 3425);
DISPLAY INVISIBLE (-5577 3425);
FORCEADD TAP..6
(-5575 3475);
FORCEPROP 3 LASTPIN (-5525 3475) SIG_NAME M_L_DQ<39>
J 0
(-5515 3485);
DISPLAY 0.659574 (-5515 3485);
PAINT MONO (-5515 3485);
DISPLAY INVISIBLE (-5515 3485);
FORCEPROP 1 LASTPIN (-5525 3475) BN 39
J 0
(-5577 3483);
DISPLAY 0.617021 (-5577 3483);
PAINT GREEN (-5577 3483);
FORCEPROP 2 LAST CDS_LIB mstr_standard
J 0
(-5575 3475);
PAINT MONO (-5575 3475);
DISPLAY INVISIBLE (-5575 3475);
FORCEPROP 1 LAST BODY_TYPE PLUMBING
J 0
(-5575 3425);
DISPLAY 1.595745 (-5575 3425);
PAINT GREEN (-5575 3425);
DISPLAY INVISIBLE (-5575 3425);
FORCEPROP 1 LAST HDL_TAP TRUE
J 0
(-5250 3350);
DISPLAY 1.595745 (-5250 3350);
PAINT GREEN (-5250 3350);
DISPLAY INVISIBLE (-5250 3350);
FORCEPROP 1 LAST PATH I61
J 0
(-5577 3475);
DISPLAY 0.872340 (-5577 3475);
PAINT GREEN (-5577 3475);
DISPLAY INVISIBLE (-5577 3475);
FORCEADD TAP..6
(-5575 3525);
FORCEPROP 3 LASTPIN (-5525 3525) SIG_NAME M_L_DQ<40>
J 0
(-5515 3535);
DISPLAY 0.659574 (-5515 3535);
PAINT MONO (-5515 3535);
DISPLAY INVISIBLE (-5515 3535);
FORCEPROP 1 LASTPIN (-5525 3525) BN 40
J 0
(-5577 3533);
DISPLAY 0.617021 (-5577 3533);
PAINT GREEN (-5577 3533);
FORCEPROP 2 LAST CDS_LIB mstr_standard
J 0
(-5575 3525);
PAINT MONO (-5575 3525);
DISPLAY INVISIBLE (-5575 3525);
FORCEPROP 1 LAST BODY_TYPE PLUMBING
J 0
(-5575 3475);
DISPLAY 1.595745 (-5575 3475);
PAINT GREEN (-5575 3475);
DISPLAY INVISIBLE (-5575 3475);
FORCEPROP 1 LAST HDL_TAP TRUE
J 0
(-5250 3400);
DISPLAY 1.595745 (-5250 3400);
PAINT GREEN (-5250 3400);
DISPLAY INVISIBLE (-5250 3400);
FORCEPROP 1 LAST PATH I62
J 0
(-5577 3525);
DISPLAY 0.872340 (-5577 3525);
PAINT GREEN (-5577 3525);
DISPLAY INVISIBLE (-5577 3525);
FORCEADD TAP..6
(-5575 3575);
FORCEPROP 3 LASTPIN (-5525 3575) SIG_NAME M_L_DQ<41>
J 0
(-5515 3585);
DISPLAY 0.659574 (-5515 3585);
PAINT MONO (-5515 3585);
DISPLAY INVISIBLE (-5515 3585);
FORCEPROP 1 LASTPIN (-5525 3575) BN 41
J 0
(-5577 3583);
DISPLAY 0.617021 (-5577 3583);
PAINT GREEN (-5577 3583);
FORCEPROP 2 LAST CDS_LIB mstr_standard
J 0
(-5575 3575);
PAINT MONO (-5575 3575);
DISPLAY INVISIBLE (-5575 3575);
FORCEPROP 1 LAST BODY_TYPE PLUMBING
J 0
(-5575 3525);
DISPLAY 1.595745 (-5575 3525);
PAINT GREEN (-5575 3525);
DISPLAY INVISIBLE (-5575 3525);
FORCEPROP 1 LAST HDL_TAP TRUE
J 0
(-5250 3450);
DISPLAY 1.595745 (-5250 3450);
PAINT GREEN (-5250 3450);
DISPLAY INVISIBLE (-5250 3450);
FORCEPROP 1 LAST PATH I63
J 0
(-5577 3575);
DISPLAY 0.872340 (-5577 3575);
PAINT GREEN (-5577 3575);
DISPLAY INVISIBLE (-5577 3575);
FORCEADD TAP..6
(-5575 3625);
FORCEPROP 3 LASTPIN (-5525 3625) SIG_NAME M_L_DQ<42>
J 0
(-5515 3635);
DISPLAY 0.659574 (-5515 3635);
PAINT MONO (-5515 3635);
DISPLAY INVISIBLE (-5515 3635);
FORCEPROP 1 LASTPIN (-5525 3625) BN 42
J 0
(-5577 3633);
DISPLAY 0.617021 (-5577 3633);
PAINT GREEN (-5577 3633);
FORCEPROP 2 LAST CDS_LIB mstr_standard
J 0
(-5575 3625);
PAINT MONO (-5575 3625);
DISPLAY INVISIBLE (-5575 3625);
FORCEPROP 1 LAST BODY_TYPE PLUMBING
J 0
(-5575 3575);
DISPLAY 1.595745 (-5575 3575);
PAINT GREEN (-5575 3575);
DISPLAY INVISIBLE (-5575 3575);
FORCEPROP 1 LAST HDL_TAP TRUE
J 0
(-5250 3500);
DISPLAY 1.595745 (-5250 3500);
PAINT GREEN (-5250 3500);
DISPLAY INVISIBLE (-5250 3500);
FORCEPROP 1 LAST PATH I64
J 0
(-5577 3625);
DISPLAY 0.872340 (-5577 3625);
PAINT GREEN (-5577 3625);
DISPLAY INVISIBLE (-5577 3625);
FORCEADD TAP..6
(-5575 3675);
FORCEPROP 3 LASTPIN (-5525 3675) SIG_NAME M_L_DQ<43>
J 0
(-5515 3685);
DISPLAY 0.659574 (-5515 3685);
PAINT MONO (-5515 3685);
DISPLAY INVISIBLE (-5515 3685);
FORCEPROP 1 LASTPIN (-5525 3675) BN 43
J 0
(-5577 3683);
DISPLAY 0.617021 (-5577 3683);
PAINT GREEN (-5577 3683);
FORCEPROP 2 LAST CDS_LIB mstr_standard
J 0
(-5575 3675);
PAINT MONO (-5575 3675);
DISPLAY INVISIBLE (-5575 3675);
FORCEPROP 1 LAST BODY_TYPE PLUMBING
J 0
(-5575 3625);
DISPLAY 1.595745 (-5575 3625);
PAINT GREEN (-5575 3625);
DISPLAY INVISIBLE (-5575 3625);
FORCEPROP 1 LAST HDL_TAP TRUE
J 0
(-5250 3550);
DISPLAY 1.595745 (-5250 3550);
PAINT GREEN (-5250 3550);
DISPLAY INVISIBLE (-5250 3550);
FORCEPROP 1 LAST PATH I65
J 0
(-5577 3675);
DISPLAY 0.872340 (-5577 3675);
PAINT GREEN (-5577 3675);
DISPLAY INVISIBLE (-5577 3675);
FORCEADD TAP..6
(-5575 3725);
FORCEPROP 3 LASTPIN (-5525 3725) SIG_NAME M_L_DQ<44>
J 0
(-5515 3735);
DISPLAY 0.659574 (-5515 3735);
PAINT MONO (-5515 3735);
DISPLAY INVISIBLE (-5515 3735);
FORCEPROP 1 LASTPIN (-5525 3725) BN 44
J 0
(-5577 3733);
DISPLAY 0.617021 (-5577 3733);
PAINT GREEN (-5577 3733);
FORCEPROP 2 LAST CDS_LIB mstr_standard
J 0
(-5575 3725);
PAINT MONO (-5575 3725);
DISPLAY INVISIBLE (-5575 3725);
FORCEPROP 1 LAST BODY_TYPE PLUMBING
J 0
(-5575 3675);
DISPLAY 1.595745 (-5575 3675);
PAINT GREEN (-5575 3675);
DISPLAY INVISIBLE (-5575 3675);
FORCEPROP 1 LAST HDL_TAP TRUE
J 0
(-5250 3600);
DISPLAY 1.595745 (-5250 3600);
PAINT GREEN (-5250 3600);
DISPLAY INVISIBLE (-5250 3600);
FORCEPROP 1 LAST PATH I66
J 0
(-5577 3725);
DISPLAY 0.872340 (-5577 3725);
PAINT GREEN (-5577 3725);
DISPLAY INVISIBLE (-5577 3725);
FORCEADD TAP..6
(-5575 3775);
FORCEPROP 3 LASTPIN (-5525 3775) SIG_NAME M_L_DQ<45>
J 0
(-5515 3785);
DISPLAY 0.659574 (-5515 3785);
PAINT MONO (-5515 3785);
DISPLAY INVISIBLE (-5515 3785);
FORCEPROP 1 LASTPIN (-5525 3775) BN 45
J 0
(-5577 3783);
DISPLAY 0.617021 (-5577 3783);
PAINT GREEN (-5577 3783);
FORCEPROP 2 LAST CDS_LIB mstr_standard
J 0
(-5575 3775);
PAINT MONO (-5575 3775);
DISPLAY INVISIBLE (-5575 3775);
FORCEPROP 1 LAST BODY_TYPE PLUMBING
J 0
(-5575 3725);
DISPLAY 1.595745 (-5575 3725);
PAINT GREEN (-5575 3725);
DISPLAY INVISIBLE (-5575 3725);
FORCEPROP 1 LAST HDL_TAP TRUE
J 0
(-5250 3650);
DISPLAY 1.595745 (-5250 3650);
PAINT GREEN (-5250 3650);
DISPLAY INVISIBLE (-5250 3650);
FORCEPROP 1 LAST PATH I67
J 0
(-5577 3775);
DISPLAY 0.872340 (-5577 3775);
PAINT GREEN (-5577 3775);
DISPLAY INVISIBLE (-5577 3775);
FORCEADD TAP..6
(-5575 3825);
FORCEPROP 3 LASTPIN (-5525 3825) SIG_NAME M_L_DQ<46>
J 0
(-5515 3835);
DISPLAY 0.659574 (-5515 3835);
PAINT MONO (-5515 3835);
DISPLAY INVISIBLE (-5515 3835);
FORCEPROP 1 LASTPIN (-5525 3825) BN 46
J 0
(-5577 3833);
DISPLAY 0.617021 (-5577 3833);
PAINT GREEN (-5577 3833);
FORCEPROP 2 LAST CDS_LIB mstr_standard
J 0
(-5575 3825);
PAINT MONO (-5575 3825);
DISPLAY INVISIBLE (-5575 3825);
FORCEPROP 1 LAST BODY_TYPE PLUMBING
J 0
(-5575 3775);
DISPLAY 1.595745 (-5575 3775);
PAINT GREEN (-5575 3775);
DISPLAY INVISIBLE (-5575 3775);
FORCEPROP 1 LAST HDL_TAP TRUE
J 0
(-5250 3700);
DISPLAY 1.595745 (-5250 3700);
PAINT GREEN (-5250 3700);
DISPLAY INVISIBLE (-5250 3700);
FORCEPROP 1 LAST PATH I68
J 0
(-5577 3825);
DISPLAY 0.872340 (-5577 3825);
PAINT GREEN (-5577 3825);
DISPLAY INVISIBLE (-5577 3825);
FORCEADD TAP..6
(-5575 3875);
FORCEPROP 3 LASTPIN (-5525 3875) SIG_NAME M_L_DQ<47>
J 0
(-5515 3885);
DISPLAY 0.659574 (-5515 3885);
PAINT MONO (-5515 3885);
DISPLAY INVISIBLE (-5515 3885);
FORCEPROP 1 LASTPIN (-5525 3875) BN 47
J 0
(-5577 3883);
DISPLAY 0.617021 (-5577 3883);
PAINT GREEN (-5577 3883);
FORCEPROP 2 LAST CDS_LIB mstr_standard
J 0
(-5575 3875);
PAINT MONO (-5575 3875);
DISPLAY INVISIBLE (-5575 3875);
FORCEPROP 1 LAST BODY_TYPE PLUMBING
J 0
(-5575 3825);
DISPLAY 1.595745 (-5575 3825);
PAINT GREEN (-5575 3825);
DISPLAY INVISIBLE (-5575 3825);
FORCEPROP 1 LAST HDL_TAP TRUE
J 0
(-5250 3750);
DISPLAY 1.595745 (-5250 3750);
PAINT GREEN (-5250 3750);
DISPLAY INVISIBLE (-5250 3750);
FORCEPROP 1 LAST PATH I69
J 0
(-5577 3875);
DISPLAY 0.872340 (-5577 3875);
PAINT GREEN (-5577 3875);
DISPLAY INVISIBLE (-5577 3875);
FORCEADD TAP..6
(-5575 775);
FORCEPROP 3 LASTPIN (-5525 775) SIG_NAME M_L_CLK_DN<3>
J 0
(-5515 785);
DISPLAY 0.659574 (-5515 785);
PAINT MONO (-5515 785);
DISPLAY INVISIBLE (-5515 785);
FORCEPROP 1 LASTPIN (-5525 775) BN 3
J 0
(-5577 783);
DISPLAY 0.617021 (-5577 783);
PAINT GREEN (-5577 783);
FORCEPROP 2 LAST CDS_LIB mstr_standard
J 0
(-5575 775);
PAINT MONO (-5575 775);
DISPLAY INVISIBLE (-5575 775);
FORCEPROP 1 LAST BODY_TYPE PLUMBING
J 0
(-5575 725);
DISPLAY 1.595745 (-5575 725);
PAINT GREEN (-5575 725);
DISPLAY INVISIBLE (-5575 725);
FORCEPROP 1 LAST HDL_TAP TRUE
J 0
(-5250 650);
DISPLAY 1.595745 (-5250 650);
PAINT GREEN (-5250 650);
DISPLAY INVISIBLE (-5250 650);
FORCEPROP 1 LAST PATH I7
J 0
(-5577 775);
DISPLAY 0.872340 (-5577 775);
PAINT GREEN (-5577 775);
DISPLAY INVISIBLE (-5577 775);
FORCEADD TAP..6
(-5575 3925);
FORCEPROP 3 LASTPIN (-5525 3925) SIG_NAME M_L_DQ<48>
J 0
(-5515 3935);
DISPLAY 0.659574 (-5515 3935);
PAINT MONO (-5515 3935);
DISPLAY INVISIBLE (-5515 3935);
FORCEPROP 1 LASTPIN (-5525 3925) BN 48
J 0
(-5577 3933);
DISPLAY 0.617021 (-5577 3933);
PAINT GREEN (-5577 3933);
FORCEPROP 2 LAST CDS_LIB mstr_standard
J 0
(-5575 3925);
PAINT MONO (-5575 3925);
DISPLAY INVISIBLE (-5575 3925);
FORCEPROP 1 LAST BODY_TYPE PLUMBING
J 0
(-5575 3875);
DISPLAY 1.595745 (-5575 3875);
PAINT GREEN (-5575 3875);
DISPLAY INVISIBLE (-5575 3875);
FORCEPROP 1 LAST HDL_TAP TRUE
J 0
(-5250 3800);
DISPLAY 1.595745 (-5250 3800);
PAINT GREEN (-5250 3800);
DISPLAY INVISIBLE (-5250 3800);
FORCEPROP 1 LAST PATH I70
J 0
(-5577 3925);
DISPLAY 0.872340 (-5577 3925);
PAINT GREEN (-5577 3925);
DISPLAY INVISIBLE (-5577 3925);
FORCEADD TAP..6
(-5575 3975);
FORCEPROP 3 LASTPIN (-5525 3975) SIG_NAME M_L_DQ<49>
J 0
(-5515 3985);
DISPLAY 0.659574 (-5515 3985);
PAINT MONO (-5515 3985);
DISPLAY INVISIBLE (-5515 3985);
FORCEPROP 1 LASTPIN (-5525 3975) BN 49
J 0
(-5577 3983);
DISPLAY 0.617021 (-5577 3983);
PAINT GREEN (-5577 3983);
FORCEPROP 2 LAST CDS_LIB mstr_standard
J 0
(-5575 3975);
PAINT MONO (-5575 3975);
DISPLAY INVISIBLE (-5575 3975);
FORCEPROP 1 LAST BODY_TYPE PLUMBING
J 0
(-5575 3925);
DISPLAY 1.595745 (-5575 3925);
PAINT GREEN (-5575 3925);
DISPLAY INVISIBLE (-5575 3925);
FORCEPROP 1 LAST HDL_TAP TRUE
J 0
(-5250 3850);
DISPLAY 1.595745 (-5250 3850);
PAINT GREEN (-5250 3850);
DISPLAY INVISIBLE (-5250 3850);
FORCEPROP 1 LAST PATH I71
J 0
(-5577 3975);
DISPLAY 0.872340 (-5577 3975);
PAINT GREEN (-5577 3975);
DISPLAY INVISIBLE (-5577 3975);
FORCEADD OFFPAGE..6
(-6425 4800);
FORCEPROP 2 LAST $XR1 86 
J 0
(-6764 4800);
DISPLAY 0.638298 (-6764 4800);
PAINT MONO (-6764 4800);
FORCEPROP 2 LAST $XR0 85 
J 0
(-6674 4800);
DISPLAY 0.638298 (-6674 4800);
PAINT MONO (-6674 4800);
FORCEPROP 2 LAST CDS_LIB mstr_standard
J 0
(-6425 4800);
PAINT MONO (-6425 4800);
DISPLAY INVISIBLE (-6425 4800);
FORCEPROP 1 LAST OFFPAGE TRUE
J 0
(-6100 4675);
DISPLAY 1.170213 (-6100 4675);
PAINT GREEN (-6100 4675);
DISPLAY INVISIBLE (-6100 4675);
FORCEPROP 1 LAST COMMENT_BODY TRUE
J 0
(-6325 4725);
DISPLAY 1.170213 (-6325 4725);
PAINT GREEN (-6325 4725);
DISPLAY INVISIBLE (-6325 4725);
FORCEPROP 2 LAST PATH I72
J 0
(-6375 4875);
DISPLAY 1.021277 (-6375 4875);
PAINT ORANGE (-6375 4875);
DISPLAY INVISIBLE (-6375 4875);
FORCEADD TAP..6
(-5575 4025);
FORCEPROP 3 LASTPIN (-5525 4025) SIG_NAME M_L_DQ<50>
J 0
(-5515 4035);
DISPLAY 0.659574 (-5515 4035);
PAINT MONO (-5515 4035);
DISPLAY INVISIBLE (-5515 4035);
FORCEPROP 1 LASTPIN (-5525 4025) BN 50
J 0
(-5577 4033);
DISPLAY 0.617021 (-5577 4033);
PAINT GREEN (-5577 4033);
FORCEPROP 2 LAST CDS_LIB mstr_standard
J 0
(-5575 4025);
PAINT MONO (-5575 4025);
DISPLAY INVISIBLE (-5575 4025);
FORCEPROP 1 LAST BODY_TYPE PLUMBING
J 0
(-5575 3975);
DISPLAY 1.595745 (-5575 3975);
PAINT GREEN (-5575 3975);
DISPLAY INVISIBLE (-5575 3975);
FORCEPROP 1 LAST HDL_TAP TRUE
J 0
(-5250 3900);
DISPLAY 1.595745 (-5250 3900);
PAINT GREEN (-5250 3900);
DISPLAY INVISIBLE (-5250 3900);
FORCEPROP 1 LAST PATH I73
J 0
(-5577 4025);
DISPLAY 0.872340 (-5577 4025);
PAINT GREEN (-5577 4025);
DISPLAY INVISIBLE (-5577 4025);
FORCEADD TAP..6
(-5575 4075);
FORCEPROP 3 LASTPIN (-5525 4075) SIG_NAME M_L_DQ<51>
J 0
(-5515 4085);
DISPLAY 0.659574 (-5515 4085);
PAINT MONO (-5515 4085);
DISPLAY INVISIBLE (-5515 4085);
FORCEPROP 1 LASTPIN (-5525 4075) BN 51
J 0
(-5577 4083);
DISPLAY 0.617021 (-5577 4083);
PAINT GREEN (-5577 4083);
FORCEPROP 2 LAST CDS_LIB mstr_standard
J 0
(-5575 4075);
PAINT MONO (-5575 4075);
DISPLAY INVISIBLE (-5575 4075);
FORCEPROP 1 LAST BODY_TYPE PLUMBING
J 0
(-5575 4025);
DISPLAY 1.595745 (-5575 4025);
PAINT GREEN (-5575 4025);
DISPLAY INVISIBLE (-5575 4025);
FORCEPROP 1 LAST HDL_TAP TRUE
J 0
(-5250 3950);
DISPLAY 1.595745 (-5250 3950);
PAINT GREEN (-5250 3950);
DISPLAY INVISIBLE (-5250 3950);
FORCEPROP 1 LAST PATH I74
J 0
(-5577 4075);
DISPLAY 0.872340 (-5577 4075);
PAINT GREEN (-5577 4075);
DISPLAY INVISIBLE (-5577 4075);
FORCEADD TAP..6
(-5575 4125);
FORCEPROP 3 LASTPIN (-5525 4125) SIG_NAME M_L_DQ<52>
J 0
(-5515 4135);
DISPLAY 0.659574 (-5515 4135);
PAINT MONO (-5515 4135);
DISPLAY INVISIBLE (-5515 4135);
FORCEPROP 1 LASTPIN (-5525 4125) BN 52
J 0
(-5577 4133);
DISPLAY 0.617021 (-5577 4133);
PAINT GREEN (-5577 4133);
FORCEPROP 2 LAST CDS_LIB mstr_standard
J 0
(-5575 4125);
PAINT MONO (-5575 4125);
DISPLAY INVISIBLE (-5575 4125);
FORCEPROP 1 LAST BODY_TYPE PLUMBING
J 0
(-5575 4075);
DISPLAY 1.595745 (-5575 4075);
PAINT GREEN (-5575 4075);
DISPLAY INVISIBLE (-5575 4075);
FORCEPROP 1 LAST HDL_TAP TRUE
J 0
(-5250 4000);
DISPLAY 1.595745 (-5250 4000);
PAINT GREEN (-5250 4000);
DISPLAY INVISIBLE (-5250 4000);
FORCEPROP 1 LAST PATH I75
J 0
(-5577 4125);
DISPLAY 0.872340 (-5577 4125);
PAINT GREEN (-5577 4125);
DISPLAY INVISIBLE (-5577 4125);
FORCEADD TAP..6
(-5575 4175);
FORCEPROP 3 LASTPIN (-5525 4175) SIG_NAME M_L_DQ<53>
J 0
(-5515 4185);
DISPLAY 0.659574 (-5515 4185);
PAINT MONO (-5515 4185);
DISPLAY INVISIBLE (-5515 4185);
FORCEPROP 1 LASTPIN (-5525 4175) BN 53
J 0
(-5577 4183);
DISPLAY 0.617021 (-5577 4183);
PAINT GREEN (-5577 4183);
FORCEPROP 2 LAST CDS_LIB mstr_standard
J 0
(-5575 4175);
PAINT MONO (-5575 4175);
DISPLAY INVISIBLE (-5575 4175);
FORCEPROP 1 LAST BODY_TYPE PLUMBING
J 0
(-5575 4125);
DISPLAY 1.595745 (-5575 4125);
PAINT GREEN (-5575 4125);
DISPLAY INVISIBLE (-5575 4125);
FORCEPROP 1 LAST HDL_TAP TRUE
J 0
(-5250 4050);
DISPLAY 1.595745 (-5250 4050);
PAINT GREEN (-5250 4050);
DISPLAY INVISIBLE (-5250 4050);
FORCEPROP 1 LAST PATH I76
J 0
(-5577 4175);
DISPLAY 0.872340 (-5577 4175);
PAINT GREEN (-5577 4175);
DISPLAY INVISIBLE (-5577 4175);
FORCEADD TAP..6
(-5575 4225);
FORCEPROP 3 LASTPIN (-5525 4225) SIG_NAME M_L_DQ<54>
J 0
(-5515 4235);
DISPLAY 0.659574 (-5515 4235);
PAINT MONO (-5515 4235);
DISPLAY INVISIBLE (-5515 4235);
FORCEPROP 1 LASTPIN (-5525 4225) BN 54
J 0
(-5577 4233);
DISPLAY 0.617021 (-5577 4233);
PAINT GREEN (-5577 4233);
FORCEPROP 2 LAST CDS_LIB mstr_standard
J 0
(-5575 4225);
PAINT MONO (-5575 4225);
DISPLAY INVISIBLE (-5575 4225);
FORCEPROP 1 LAST BODY_TYPE PLUMBING
J 0
(-5575 4175);
DISPLAY 1.595745 (-5575 4175);
PAINT GREEN (-5575 4175);
DISPLAY INVISIBLE (-5575 4175);
FORCEPROP 1 LAST HDL_TAP TRUE
J 0
(-5250 4100);
DISPLAY 1.595745 (-5250 4100);
PAINT GREEN (-5250 4100);
DISPLAY INVISIBLE (-5250 4100);
FORCEPROP 1 LAST PATH I77
J 0
(-5577 4225);
DISPLAY 0.872340 (-5577 4225);
PAINT GREEN (-5577 4225);
DISPLAY INVISIBLE (-5577 4225);
FORCEADD TAP..6
(-5575 4275);
FORCEPROP 3 LASTPIN (-5525 4275) SIG_NAME M_L_DQ<55>
J 0
(-5515 4285);
DISPLAY 0.659574 (-5515 4285);
PAINT MONO (-5515 4285);
DISPLAY INVISIBLE (-5515 4285);
FORCEPROP 1 LASTPIN (-5525 4275) BN 55
J 0
(-5577 4283);
DISPLAY 0.617021 (-5577 4283);
PAINT GREEN (-5577 4283);
FORCEPROP 2 LAST CDS_LIB mstr_standard
J 0
(-5575 4275);
PAINT MONO (-5575 4275);
DISPLAY INVISIBLE (-5575 4275);
FORCEPROP 1 LAST BODY_TYPE PLUMBING
J 0
(-5575 4225);
DISPLAY 1.595745 (-5575 4225);
PAINT GREEN (-5575 4225);
DISPLAY INVISIBLE (-5575 4225);
FORCEPROP 1 LAST HDL_TAP TRUE
J 0
(-5250 4150);
DISPLAY 1.595745 (-5250 4150);
PAINT GREEN (-5250 4150);
DISPLAY INVISIBLE (-5250 4150);
FORCEPROP 1 LAST PATH I78
J 0
(-5577 4275);
DISPLAY 0.872340 (-5577 4275);
PAINT GREEN (-5577 4275);
DISPLAY INVISIBLE (-5577 4275);
FORCEADD TAP..6
(-5575 4325);
FORCEPROP 3 LASTPIN (-5525 4325) SIG_NAME M_L_DQ<56>
J 0
(-5515 4335);
DISPLAY 0.659574 (-5515 4335);
PAINT MONO (-5515 4335);
DISPLAY INVISIBLE (-5515 4335);
FORCEPROP 1 LASTPIN (-5525 4325) BN 56
J 0
(-5577 4333);
DISPLAY 0.617021 (-5577 4333);
PAINT GREEN (-5577 4333);
FORCEPROP 2 LAST CDS_LIB mstr_standard
J 0
(-5575 4325);
PAINT MONO (-5575 4325);
DISPLAY INVISIBLE (-5575 4325);
FORCEPROP 1 LAST BODY_TYPE PLUMBING
J 0
(-5575 4275);
DISPLAY 1.595745 (-5575 4275);
PAINT GREEN (-5575 4275);
DISPLAY INVISIBLE (-5575 4275);
FORCEPROP 1 LAST HDL_TAP TRUE
J 0
(-5250 4200);
DISPLAY 1.595745 (-5250 4200);
PAINT GREEN (-5250 4200);
DISPLAY INVISIBLE (-5250 4200);
FORCEPROP 1 LAST PATH I79
J 0
(-5577 4325);
DISPLAY 0.872340 (-5577 4325);
PAINT GREEN (-5577 4325);
DISPLAY INVISIBLE (-5577 4325);
FORCEADD TAP..6
(-5575 725);
FORCEPROP 3 LASTPIN (-5525 725) SIG_NAME M_L_CLK_DN<2>
J 0
(-5515 735);
DISPLAY 0.659574 (-5515 735);
PAINT MONO (-5515 735);
DISPLAY INVISIBLE (-5515 735);
FORCEPROP 1 LASTPIN (-5525 725) BN 2
J 0
(-5577 733);
DISPLAY 0.617021 (-5577 733);
PAINT GREEN (-5577 733);
FORCEPROP 2 LAST CDS_LIB mstr_standard
J 0
(-5575 725);
PAINT MONO (-5575 725);
DISPLAY INVISIBLE (-5575 725);
FORCEPROP 1 LAST BODY_TYPE PLUMBING
J 0
(-5575 675);
DISPLAY 1.595745 (-5575 675);
PAINT GREEN (-5575 675);
DISPLAY INVISIBLE (-5575 675);
FORCEPROP 1 LAST HDL_TAP TRUE
J 0
(-5250 600);
DISPLAY 1.595745 (-5250 600);
PAINT GREEN (-5250 600);
DISPLAY INVISIBLE (-5250 600);
FORCEPROP 1 LAST PATH I8
J 0
(-5577 725);
DISPLAY 0.872340 (-5577 725);
PAINT GREEN (-5577 725);
DISPLAY INVISIBLE (-5577 725);
FORCEADD TAP..6
(-5575 4375);
FORCEPROP 3 LASTPIN (-5525 4375) SIG_NAME M_L_DQ<57>
J 0
(-5515 4385);
DISPLAY 0.659574 (-5515 4385);
PAINT MONO (-5515 4385);
DISPLAY INVISIBLE (-5515 4385);
FORCEPROP 1 LASTPIN (-5525 4375) BN 57
J 0
(-5577 4383);
DISPLAY 0.617021 (-5577 4383);
PAINT GREEN (-5577 4383);
FORCEPROP 2 LAST CDS_LIB mstr_standard
J 0
(-5575 4375);
PAINT MONO (-5575 4375);
DISPLAY INVISIBLE (-5575 4375);
FORCEPROP 1 LAST BODY_TYPE PLUMBING
J 0
(-5575 4325);
DISPLAY 1.595745 (-5575 4325);
PAINT GREEN (-5575 4325);
DISPLAY INVISIBLE (-5575 4325);
FORCEPROP 1 LAST HDL_TAP TRUE
J 0
(-5250 4250);
DISPLAY 1.595745 (-5250 4250);
PAINT GREEN (-5250 4250);
DISPLAY INVISIBLE (-5250 4250);
FORCEPROP 1 LAST PATH I80
J 0
(-5577 4375);
DISPLAY 0.872340 (-5577 4375);
PAINT GREEN (-5577 4375);
DISPLAY INVISIBLE (-5577 4375);
FORCEADD TAP..6
(-5575 4425);
FORCEPROP 3 LASTPIN (-5525 4425) SIG_NAME M_L_DQ<58>
J 0
(-5515 4435);
DISPLAY 0.659574 (-5515 4435);
PAINT MONO (-5515 4435);
DISPLAY INVISIBLE (-5515 4435);
FORCEPROP 1 LASTPIN (-5525 4425) BN 58
J 0
(-5577 4433);
DISPLAY 0.617021 (-5577 4433);
PAINT GREEN (-5577 4433);
FORCEPROP 2 LAST CDS_LIB mstr_standard
J 0
(-5575 4425);
PAINT MONO (-5575 4425);
DISPLAY INVISIBLE (-5575 4425);
FORCEPROP 1 LAST BODY_TYPE PLUMBING
J 0
(-5575 4375);
DISPLAY 1.595745 (-5575 4375);
PAINT GREEN (-5575 4375);
DISPLAY INVISIBLE (-5575 4375);
FORCEPROP 1 LAST HDL_TAP TRUE
J 0
(-5250 4300);
DISPLAY 1.595745 (-5250 4300);
PAINT GREEN (-5250 4300);
DISPLAY INVISIBLE (-5250 4300);
FORCEPROP 1 LAST PATH I81
J 0
(-5577 4425);
DISPLAY 0.872340 (-5577 4425);
PAINT GREEN (-5577 4425);
DISPLAY INVISIBLE (-5577 4425);
FORCEADD TAP..6
(-5575 4475);
FORCEPROP 3 LASTPIN (-5525 4475) SIG_NAME M_L_DQ<59>
J 0
(-5515 4485);
DISPLAY 0.659574 (-5515 4485);
PAINT MONO (-5515 4485);
DISPLAY INVISIBLE (-5515 4485);
FORCEPROP 1 LASTPIN (-5525 4475) BN 59
J 0
(-5577 4483);
DISPLAY 0.617021 (-5577 4483);
PAINT GREEN (-5577 4483);
FORCEPROP 2 LAST CDS_LIB mstr_standard
J 0
(-5575 4475);
PAINT MONO (-5575 4475);
DISPLAY INVISIBLE (-5575 4475);
FORCEPROP 1 LAST BODY_TYPE PLUMBING
J 0
(-5575 4425);
DISPLAY 1.595745 (-5575 4425);
PAINT GREEN (-5575 4425);
DISPLAY INVISIBLE (-5575 4425);
FORCEPROP 1 LAST HDL_TAP TRUE
J 0
(-5250 4350);
DISPLAY 1.595745 (-5250 4350);
PAINT GREEN (-5250 4350);
DISPLAY INVISIBLE (-5250 4350);
FORCEPROP 1 LAST PATH I82
J 0
(-5577 4475);
DISPLAY 0.872340 (-5577 4475);
PAINT GREEN (-5577 4475);
DISPLAY INVISIBLE (-5577 4475);
FORCEADD TAP..6
(-5575 4525);
FORCEPROP 3 LASTPIN (-5525 4525) SIG_NAME M_L_DQ<60>
J 0
(-5515 4535);
DISPLAY 0.659574 (-5515 4535);
PAINT MONO (-5515 4535);
DISPLAY INVISIBLE (-5515 4535);
FORCEPROP 1 LASTPIN (-5525 4525) BN 60
J 0
(-5577 4533);
DISPLAY 0.617021 (-5577 4533);
PAINT GREEN (-5577 4533);
FORCEPROP 2 LAST CDS_LIB mstr_standard
J 0
(-5575 4525);
PAINT MONO (-5575 4525);
DISPLAY INVISIBLE (-5575 4525);
FORCEPROP 1 LAST BODY_TYPE PLUMBING
J 0
(-5575 4475);
DISPLAY 1.595745 (-5575 4475);
PAINT GREEN (-5575 4475);
DISPLAY INVISIBLE (-5575 4475);
FORCEPROP 1 LAST HDL_TAP TRUE
J 0
(-5250 4400);
DISPLAY 1.595745 (-5250 4400);
PAINT GREEN (-5250 4400);
DISPLAY INVISIBLE (-5250 4400);
FORCEPROP 1 LAST PATH I83
J 0
(-5577 4525);
DISPLAY 0.872340 (-5577 4525);
PAINT GREEN (-5577 4525);
DISPLAY INVISIBLE (-5577 4525);
FORCEADD TAP..6
(-5575 4575);
FORCEPROP 3 LASTPIN (-5525 4575) SIG_NAME M_L_DQ<61>
J 0
(-5515 4585);
DISPLAY 0.659574 (-5515 4585);
PAINT MONO (-5515 4585);
DISPLAY INVISIBLE (-5515 4585);
FORCEPROP 1 LASTPIN (-5525 4575) BN 61
J 0
(-5577 4583);
DISPLAY 0.617021 (-5577 4583);
PAINT GREEN (-5577 4583);
FORCEPROP 2 LAST CDS_LIB mstr_standard
J 0
(-5575 4575);
PAINT MONO (-5575 4575);
DISPLAY INVISIBLE (-5575 4575);
FORCEPROP 1 LAST BODY_TYPE PLUMBING
J 0
(-5575 4525);
DISPLAY 1.595745 (-5575 4525);
PAINT GREEN (-5575 4525);
DISPLAY INVISIBLE (-5575 4525);
FORCEPROP 1 LAST HDL_TAP TRUE
J 0
(-5250 4450);
DISPLAY 1.595745 (-5250 4450);
PAINT GREEN (-5250 4450);
DISPLAY INVISIBLE (-5250 4450);
FORCEPROP 1 LAST PATH I84
J 0
(-5577 4575);
DISPLAY 0.872340 (-5577 4575);
PAINT GREEN (-5577 4575);
DISPLAY INVISIBLE (-5577 4575);
FORCEADD TAP..6
(-5575 4625);
FORCEPROP 3 LASTPIN (-5525 4625) SIG_NAME M_L_DQ<62>
J 0
(-5515 4635);
DISPLAY 0.659574 (-5515 4635);
PAINT MONO (-5515 4635);
DISPLAY INVISIBLE (-5515 4635);
FORCEPROP 1 LASTPIN (-5525 4625) BN 62
J 0
(-5577 4633);
DISPLAY 0.617021 (-5577 4633);
PAINT GREEN (-5577 4633);
FORCEPROP 2 LAST CDS_LIB mstr_standard
J 0
(-5575 4625);
PAINT MONO (-5575 4625);
DISPLAY INVISIBLE (-5575 4625);
FORCEPROP 1 LAST BODY_TYPE PLUMBING
J 0
(-5575 4575);
DISPLAY 1.595745 (-5575 4575);
PAINT GREEN (-5575 4575);
DISPLAY INVISIBLE (-5575 4575);
FORCEPROP 1 LAST HDL_TAP TRUE
J 0
(-5250 4500);
DISPLAY 1.595745 (-5250 4500);
PAINT GREEN (-5250 4500);
DISPLAY INVISIBLE (-5250 4500);
FORCEPROP 1 LAST PATH I85
J 0
(-5577 4625);
DISPLAY 0.872340 (-5577 4625);
PAINT GREEN (-5577 4625);
DISPLAY INVISIBLE (-5577 4625);
FORCEADD TAP..6
(-5575 4675);
FORCEPROP 3 LASTPIN (-5525 4675) SIG_NAME M_L_DQ<63>
J 0
(-5515 4685);
DISPLAY 0.659574 (-5515 4685);
PAINT MONO (-5515 4685);
DISPLAY INVISIBLE (-5515 4685);
FORCEPROP 1 LASTPIN (-5525 4675) BN 63
J 0
(-5577 4683);
DISPLAY 0.617021 (-5577 4683);
PAINT GREEN (-5577 4683);
FORCEPROP 2 LAST CDS_LIB mstr_standard
J 0
(-5575 4675);
PAINT MONO (-5575 4675);
DISPLAY INVISIBLE (-5575 4675);
FORCEPROP 1 LAST BODY_TYPE PLUMBING
J 0
(-5575 4625);
DISPLAY 1.595745 (-5575 4625);
PAINT GREEN (-5575 4625);
DISPLAY INVISIBLE (-5575 4625);
FORCEPROP 1 LAST HDL_TAP TRUE
J 0
(-5250 4550);
DISPLAY 1.595745 (-5250 4550);
PAINT GREEN (-5250 4550);
DISPLAY INVISIBLE (-5250 4550);
FORCEPROP 1 LAST PATH I86
J 0
(-5577 4675);
DISPLAY 0.872340 (-5577 4675);
PAINT GREEN (-5577 4675);
DISPLAY INVISIBLE (-5577 4675);
FORCEADD TAP..6
R 2
(-2850 775);
FORCEPROP 3 LASTPIN (-2900 775) SIG_NAME M_L_BA<1>
J 0
(-2890 785);
DISPLAY 0.659574 (-2890 785);
PAINT MONO (-2890 785);
DISPLAY INVISIBLE (-2890 785);
FORCEPROP 1 LASTPIN (-2900 775) BN 1
J 2
(-2848 783);
DISPLAY 0.617021 (-2848 783);
PAINT GREEN (-2848 783);
FORCEPROP 2 LAST CDS_LIB mstr_standard
J 0
(-2850 775);
PAINT MONO (-2850 775);
DISPLAY INVISIBLE (-2850 775);
FORCEPROP 1 LAST BODY_TYPE PLUMBING
J 2
(-2850 725);
DISPLAY 1.595745 (-2850 725);
PAINT GREEN (-2850 725);
DISPLAY INVISIBLE (-2850 725);
FORCEPROP 1 LAST HDL_TAP TRUE
J 2
(-3175 650);
DISPLAY 1.595745 (-3175 650);
PAINT GREEN (-3175 650);
DISPLAY INVISIBLE (-3175 650);
FORCEPROP 1 LAST PATH I87
J 2
(-2848 775);
DISPLAY 0.872340 (-2848 775);
PAINT GREEN (-2848 775);
DISPLAY INVISIBLE (-2848 775);
FORCEADD TAP..6
R 2
(-2850 725);
FORCEPROP 3 LASTPIN (-2900 725) SIG_NAME M_L_BA<0>
J 0
(-2890 735);
DISPLAY 0.659574 (-2890 735);
PAINT MONO (-2890 735);
DISPLAY INVISIBLE (-2890 735);
FORCEPROP 1 LASTPIN (-2900 725) BN 0
J 2
(-2848 733);
DISPLAY 0.617021 (-2848 733);
PAINT GREEN (-2848 733);
FORCEPROP 2 LAST CDS_LIB mstr_standard
J 0
(-2850 725);
PAINT MONO (-2850 725);
DISPLAY INVISIBLE (-2850 725);
FORCEPROP 1 LAST BODY_TYPE PLUMBING
J 2
(-2850 675);
DISPLAY 1.595745 (-2850 675);
PAINT GREEN (-2850 675);
DISPLAY INVISIBLE (-2850 675);
FORCEPROP 1 LAST HDL_TAP TRUE
J 2
(-3175 600);
DISPLAY 1.595745 (-3175 600);
PAINT GREEN (-3175 600);
DISPLAY INVISIBLE (-3175 600);
FORCEPROP 1 LAST PATH I88
J 2
(-2848 725);
DISPLAY 0.872340 (-2848 725);
PAINT GREEN (-2848 725);
DISPLAY INVISIBLE (-2848 725);
FORCEADD TAP..6
R 2
(-2850 825);
FORCEPROP 3 LASTPIN (-2900 825) SIG_NAME M_L_BG<0>
J 0
(-2890 835);
DISPLAY 0.659574 (-2890 835);
PAINT MONO (-2890 835);
DISPLAY INVISIBLE (-2890 835);
FORCEPROP 1 LASTPIN (-2900 825) BN 0
J 2
(-2848 833);
DISPLAY 0.617021 (-2848 833);
PAINT GREEN (-2848 833);
FORCEPROP 2 LAST CDS_LIB mstr_standard
J 0
(-2850 825);
PAINT MONO (-2850 825);
DISPLAY INVISIBLE (-2850 825);
FORCEPROP 1 LAST BODY_TYPE PLUMBING
J 2
(-2850 775);
DISPLAY 1.595745 (-2850 775);
PAINT GREEN (-2850 775);
DISPLAY INVISIBLE (-2850 775);
FORCEPROP 1 LAST HDL_TAP TRUE
J 2
(-3175 700);
DISPLAY 1.595745 (-3175 700);
PAINT GREEN (-3175 700);
DISPLAY INVISIBLE (-3175 700);
FORCEPROP 1 LAST PATH I89
J 2
(-2848 825);
DISPLAY 0.872340 (-2848 825);
PAINT GREEN (-2848 825);
DISPLAY INVISIBLE (-2848 825);
FORCEADD TAP..6
(-5575 875);
FORCEPROP 3 LASTPIN (-5525 875) SIG_NAME M_L_CLK_DP<1>
J 0
(-5515 885);
DISPLAY 0.659574 (-5515 885);
PAINT MONO (-5515 885);
DISPLAY INVISIBLE (-5515 885);
FORCEPROP 1 LASTPIN (-5525 875) BN 1
J 0
(-5577 883);
DISPLAY 0.617021 (-5577 883);
PAINT GREEN (-5577 883);
FORCEPROP 2 LAST CDS_LIB mstr_standard
J 0
(-5575 875);
PAINT MONO (-5575 875);
DISPLAY INVISIBLE (-5575 875);
FORCEPROP 1 LAST BODY_TYPE PLUMBING
J 0
(-5575 825);
DISPLAY 1.595745 (-5575 825);
PAINT GREEN (-5575 825);
DISPLAY INVISIBLE (-5575 825);
FORCEPROP 1 LAST HDL_TAP TRUE
J 0
(-5250 750);
DISPLAY 1.595745 (-5250 750);
PAINT GREEN (-5250 750);
DISPLAY INVISIBLE (-5250 750);
FORCEPROP 1 LAST PATH I9
J 0
(-5577 875);
DISPLAY 0.872340 (-5577 875);
PAINT GREEN (-5577 875);
DISPLAY INVISIBLE (-5577 875);
FORCEADD TAP..6
R 2
(-2850 875);
FORCEPROP 3 LASTPIN (-2900 875) SIG_NAME M_L_BG<1>
J 0
(-2890 885);
DISPLAY 0.659574 (-2890 885);
PAINT MONO (-2890 885);
DISPLAY INVISIBLE (-2890 885);
FORCEPROP 1 LASTPIN (-2900 875) BN 1
J 2
(-2848 883);
DISPLAY 0.617021 (-2848 883);
PAINT GREEN (-2848 883);
FORCEPROP 2 LAST CDS_LIB mstr_standard
J 0
(-2850 875);
PAINT MONO (-2850 875);
DISPLAY INVISIBLE (-2850 875);
FORCEPROP 1 LAST BODY_TYPE PLUMBING
J 2
(-2850 825);
DISPLAY 1.595745 (-2850 825);
PAINT GREEN (-2850 825);
DISPLAY INVISIBLE (-2850 825);
FORCEPROP 1 LAST HDL_TAP TRUE
J 2
(-3175 750);
DISPLAY 1.595745 (-3175 750);
PAINT GREEN (-3175 750);
DISPLAY INVISIBLE (-3175 750);
FORCEPROP 1 LAST PATH I90
J 2
(-2848 875);
DISPLAY 0.872340 (-2848 875);
PAINT GREEN (-2848 875);
DISPLAY INVISIBLE (-2848 875);
FORCEADD TAP..6
R 2
(-2850 1075);
FORCEPROP 3 LASTPIN (-2900 1075) SIG_NAME M_L_CS_N<2>
J 0
(-2890 1085);
DISPLAY 0.659574 (-2890 1085);
PAINT MONO (-2890 1085);
DISPLAY INVISIBLE (-2890 1085);
FORCEPROP 1 LASTPIN (-2900 1075) BN 2
J 2
(-2848 1083);
DISPLAY 0.617021 (-2848 1083);
PAINT GREEN (-2848 1083);
FORCEPROP 2 LAST CDS_LIB mstr_standard
J 0
(-2850 1075);
PAINT MONO (-2850 1075);
DISPLAY INVISIBLE (-2850 1075);
FORCEPROP 1 LAST BODY_TYPE PLUMBING
J 2
(-2850 1025);
DISPLAY 1.595745 (-2850 1025);
PAINT GREEN (-2850 1025);
DISPLAY INVISIBLE (-2850 1025);
FORCEPROP 1 LAST HDL_TAP TRUE
J 2
(-3175 950);
DISPLAY 1.595745 (-3175 950);
PAINT GREEN (-3175 950);
DISPLAY INVISIBLE (-3175 950);
FORCEPROP 1 LAST PATH I91
J 2
(-2848 1075);
DISPLAY 0.872340 (-2848 1075);
PAINT GREEN (-2848 1075);
DISPLAY INVISIBLE (-2848 1075);
FORCEADD TAP..6
R 2
(-2850 1025);
FORCEPROP 3 LASTPIN (-2900 1025) SIG_NAME M_L_CS_N<1>
J 0
(-2890 1035);
DISPLAY 0.659574 (-2890 1035);
PAINT MONO (-2890 1035);
DISPLAY INVISIBLE (-2890 1035);
FORCEPROP 1 LASTPIN (-2900 1025) BN 1
J 2
(-2848 1033);
DISPLAY 0.617021 (-2848 1033);
PAINT GREEN (-2848 1033);
FORCEPROP 2 LAST CDS_LIB mstr_standard
J 0
(-2850 1025);
PAINT MONO (-2850 1025);
DISPLAY INVISIBLE (-2850 1025);
FORCEPROP 1 LAST BODY_TYPE PLUMBING
J 2
(-2850 975);
DISPLAY 1.595745 (-2850 975);
PAINT GREEN (-2850 975);
DISPLAY INVISIBLE (-2850 975);
FORCEPROP 1 LAST HDL_TAP TRUE
J 2
(-3175 900);
DISPLAY 1.595745 (-3175 900);
PAINT GREEN (-3175 900);
DISPLAY INVISIBLE (-3175 900);
FORCEPROP 1 LAST PATH I92
J 2
(-2848 1025);
DISPLAY 0.872340 (-2848 1025);
PAINT GREEN (-2848 1025);
DISPLAY INVISIBLE (-2848 1025);
FORCEADD TAP..6
R 2
(-2850 975);
FORCEPROP 3 LASTPIN (-2900 975) SIG_NAME M_L_CS_N<0>
J 0
(-2890 985);
DISPLAY 0.659574 (-2890 985);
PAINT MONO (-2890 985);
DISPLAY INVISIBLE (-2890 985);
FORCEPROP 1 LASTPIN (-2900 975) BN 0
J 2
(-2848 983);
DISPLAY 0.617021 (-2848 983);
PAINT GREEN (-2848 983);
FORCEPROP 2 LAST CDS_LIB mstr_standard
J 0
(-2850 975);
PAINT MONO (-2850 975);
DISPLAY INVISIBLE (-2850 975);
FORCEPROP 1 LAST BODY_TYPE PLUMBING
J 2
(-2850 925);
DISPLAY 1.595745 (-2850 925);
PAINT GREEN (-2850 925);
DISPLAY INVISIBLE (-2850 925);
FORCEPROP 1 LAST HDL_TAP TRUE
J 2
(-3175 850);
DISPLAY 1.595745 (-3175 850);
PAINT GREEN (-3175 850);
DISPLAY INVISIBLE (-3175 850);
FORCEPROP 1 LAST PATH I93
J 2
(-2848 975);
DISPLAY 0.872340 (-2848 975);
PAINT GREEN (-2848 975);
DISPLAY INVISIBLE (-2848 975);
FORCEADD TAP..6
R 2
(-2850 1175);
FORCEPROP 3 LASTPIN (-2900 1175) SIG_NAME M_L_CS_N<4>
J 0
(-2890 1185);
DISPLAY 0.659574 (-2890 1185);
PAINT MONO (-2890 1185);
DISPLAY INVISIBLE (-2890 1185);
FORCEPROP 1 LASTPIN (-2900 1175) BN 4
J 2
(-2848 1183);
DISPLAY 0.617021 (-2848 1183);
PAINT GREEN (-2848 1183);
FORCEPROP 2 LAST CDS_LIB mstr_standard
J 0
(-2850 1175);
PAINT MONO (-2850 1175);
DISPLAY INVISIBLE (-2850 1175);
FORCEPROP 1 LAST BODY_TYPE PLUMBING
J 2
(-2850 1125);
DISPLAY 1.595745 (-2850 1125);
PAINT GREEN (-2850 1125);
DISPLAY INVISIBLE (-2850 1125);
FORCEPROP 1 LAST HDL_TAP TRUE
J 2
(-3175 1050);
DISPLAY 1.595745 (-3175 1050);
PAINT GREEN (-3175 1050);
DISPLAY INVISIBLE (-3175 1050);
FORCEPROP 1 LAST PATH I94
J 2
(-2848 1175);
DISPLAY 0.872340 (-2848 1175);
PAINT GREEN (-2848 1175);
DISPLAY INVISIBLE (-2848 1175);
FORCEADD TAP..6
R 2
(-2850 1125);
FORCEPROP 3 LASTPIN (-2900 1125) SIG_NAME M_L_CS_N<3>
J 0
(-2890 1135);
DISPLAY 0.659574 (-2890 1135);
PAINT MONO (-2890 1135);
DISPLAY INVISIBLE (-2890 1135);
FORCEPROP 1 LASTPIN (-2900 1125) BN 3
J 2
(-2848 1133);
DISPLAY 0.617021 (-2848 1133);
PAINT GREEN (-2848 1133);
FORCEPROP 2 LAST CDS_LIB mstr_standard
J 0
(-2850 1125);
PAINT MONO (-2850 1125);
DISPLAY INVISIBLE (-2850 1125);
FORCEPROP 1 LAST BODY_TYPE PLUMBING
J 2
(-2850 1075);
DISPLAY 1.595745 (-2850 1075);
PAINT GREEN (-2850 1075);
DISPLAY INVISIBLE (-2850 1075);
FORCEPROP 1 LAST HDL_TAP TRUE
J 2
(-3175 1000);
DISPLAY 1.595745 (-3175 1000);
PAINT GREEN (-3175 1000);
DISPLAY INVISIBLE (-3175 1000);
FORCEPROP 1 LAST PATH I95
J 2
(-2848 1125);
DISPLAY 0.872340 (-2848 1125);
PAINT GREEN (-2848 1125);
DISPLAY INVISIBLE (-2848 1125);
FORCEADD TAP..6
R 2
(-2850 1225);
FORCEPROP 3 LASTPIN (-2900 1225) SIG_NAME M_L_CS_N<5>
J 0
(-2890 1235);
DISPLAY 0.659574 (-2890 1235);
PAINT MONO (-2890 1235);
DISPLAY INVISIBLE (-2890 1235);
FORCEPROP 1 LASTPIN (-2900 1225) BN 5
J 2
(-2848 1233);
DISPLAY 0.617021 (-2848 1233);
PAINT GREEN (-2848 1233);
FORCEPROP 2 LAST CDS_LIB mstr_standard
J 0
(-2850 1225);
PAINT MONO (-2850 1225);
DISPLAY INVISIBLE (-2850 1225);
FORCEPROP 1 LAST BODY_TYPE PLUMBING
J 2
(-2850 1175);
DISPLAY 1.595745 (-2850 1175);
PAINT GREEN (-2850 1175);
DISPLAY INVISIBLE (-2850 1175);
FORCEPROP 1 LAST HDL_TAP TRUE
J 2
(-3175 1100);
DISPLAY 1.595745 (-3175 1100);
PAINT GREEN (-3175 1100);
DISPLAY INVISIBLE (-3175 1100);
FORCEPROP 1 LAST PATH I96
J 2
(-2848 1225);
DISPLAY 0.872340 (-2848 1225);
PAINT GREEN (-2848 1225);
DISPLAY INVISIBLE (-2848 1225);
FORCEADD TAP..6
R 2
(-2850 1275);
FORCEPROP 3 LASTPIN (-2900 1275) SIG_NAME M_L_CS_N<6>
J 0
(-2890 1285);
DISPLAY 0.659574 (-2890 1285);
PAINT MONO (-2890 1285);
DISPLAY INVISIBLE (-2890 1285);
FORCEPROP 1 LASTPIN (-2900 1275) BN 6
J 2
(-2848 1283);
DISPLAY 0.617021 (-2848 1283);
PAINT GREEN (-2848 1283);
FORCEPROP 2 LAST CDS_LIB mstr_standard
J 0
(-2850 1275);
PAINT MONO (-2850 1275);
DISPLAY INVISIBLE (-2850 1275);
FORCEPROP 1 LAST BODY_TYPE PLUMBING
J 2
(-2850 1225);
DISPLAY 1.595745 (-2850 1225);
PAINT GREEN (-2850 1225);
DISPLAY INVISIBLE (-2850 1225);
FORCEPROP 1 LAST HDL_TAP TRUE
J 2
(-3175 1150);
DISPLAY 1.595745 (-3175 1150);
PAINT GREEN (-3175 1150);
DISPLAY INVISIBLE (-3175 1150);
FORCEPROP 1 LAST PATH I97
J 2
(-2848 1275);
DISPLAY 0.872340 (-2848 1275);
PAINT GREEN (-2848 1275);
DISPLAY INVISIBLE (-2848 1275);
FORCEADD TAP..6
R 2
(-2850 1325);
FORCEPROP 3 LASTPIN (-2900 1325) SIG_NAME M_L_CS_N<7>
J 0
(-2890 1335);
DISPLAY 0.659574 (-2890 1335);
PAINT MONO (-2890 1335);
DISPLAY INVISIBLE (-2890 1335);
FORCEPROP 1 LASTPIN (-2900 1325) BN 7
J 2
(-2848 1333);
DISPLAY 0.617021 (-2848 1333);
PAINT GREEN (-2848 1333);
FORCEPROP 2 LAST CDS_LIB mstr_standard
J 0
(-2850 1325);
PAINT MONO (-2850 1325);
DISPLAY INVISIBLE (-2850 1325);
FORCEPROP 1 LAST BODY_TYPE PLUMBING
J 2
(-2850 1275);
DISPLAY 1.595745 (-2850 1275);
PAINT GREEN (-2850 1275);
DISPLAY INVISIBLE (-2850 1275);
FORCEPROP 1 LAST HDL_TAP TRUE
J 2
(-3175 1200);
DISPLAY 1.595745 (-3175 1200);
PAINT GREEN (-3175 1200);
DISPLAY INVISIBLE (-3175 1200);
FORCEPROP 1 LAST PATH I98
J 2
(-2848 1325);
DISPLAY 0.872340 (-2848 1325);
PAINT GREEN (-2848 1325);
DISPLAY INVISIBLE (-2848 1325);
FORCEADD TAP..6
R 2
(-2850 1425);
FORCEPROP 3 LASTPIN (-2900 1425) SIG_NAME M_L_ODT<0>
J 0
(-2890 1435);
DISPLAY 0.659574 (-2890 1435);
PAINT MONO (-2890 1435);
DISPLAY INVISIBLE (-2890 1435);
FORCEPROP 1 LASTPIN (-2900 1425) BN 0
J 2
(-2848 1433);
DISPLAY 0.617021 (-2848 1433);
PAINT GREEN (-2848 1433);
FORCEPROP 2 LAST CDS_LIB mstr_standard
J 0
(-2850 1425);
PAINT MONO (-2850 1425);
DISPLAY INVISIBLE (-2850 1425);
FORCEPROP 1 LAST BODY_TYPE PLUMBING
J 2
(-2850 1375);
DISPLAY 1.595745 (-2850 1375);
PAINT GREEN (-2850 1375);
DISPLAY INVISIBLE (-2850 1375);
FORCEPROP 1 LAST HDL_TAP TRUE
J 2
(-3175 1300);
DISPLAY 1.595745 (-3175 1300);
PAINT GREEN (-3175 1300);
DISPLAY INVISIBLE (-3175 1300);
FORCEPROP 1 LAST PATH I99
J 2
(-2848 1425);
DISPLAY 0.872340 (-2848 1425);
PAINT GREEN (-2848 1425);
DISPLAY INVISIBLE (-2848 1425);
FORCEADD DESIGN_NOTE..1
(-6400 400);
FORCEPROP 0 LAST L1 CPU SYMBOLS 1-30 ARE PRELIMINARY AND SUBJECT TO CHANGE
J 0
(-6600 275);
DISPLAY 1.021277 (-6600 275);
PAINT ORANGE (-6600 275);
FORCEPROP 2 LAST CDS_LIB mstr_symbols
J 0
(-6400 400);
PAINT ORANGE (-6400 400);
DISPLAY INVISIBLE (-6400 400);
FORCEPROP 1 LAST COMMENT_BODY TRUE
J 0
(-6375 500);
DISPLAY 0.978723 (-6375 500);
PAINT ORANGE (-6375 500);
DISPLAY INVISIBLE (-6375 500);
FORCEADD PRELIM..10
(-4215 2565);
PAINT GRAY (-4215 2565);
FORCEPROP 2 LAST CDS_LIB mstr_misc
J 0
(-4215 2565);
PAINT ORANGE (-4215 2565);
DISPLAY INVISIBLE (-4215 2565);
FORCEPROP 1 LAST COMMENT_BODY TRUE
J 0
(-4215 2565);
PAINT ORANGE (-4215 2565);
DISPLAY INVISIBLE (-4215 2565);
FORCEADD INTEL_CORP_BPAGE..1
(0 0);
FORCEPROP 1 LAST CDS_CON_LAST_MODIFIED Fri Jun 16 17:48:24 2017
J 0
(-1425 325);
DISPLAY 1.340426 (-1425 325);
PAINT GREEN (-1425 325);
DISPLAY INVISIBLE (-1425 325);
FORCEPROP 1 LAST CUSTOM_TXT_CDS <CURRENT_DESIGN_SHEET> OF <TOTAL_DESIGN_SHEETS>
J 0
(-500 25);
PAINT ORANGE (-500 25);
FORCEPROP 1 LAST CUSTOM_TXT_CDS <CON_LAST_MODIFIED>
J 0
(-4000 100);
PAINT ORANGE (-4000 100);
FORCEPROP 2 LAST CUSTOM_TXT_CDS <XR_PAGE_TITLE>
J 0
(-7890 5250);
DISPLAY 0.638298 (-7890 5250);
PAINT PINK (-7890 5250);
DISPLAY INVISIBLE (-7890 5250);
FORCEPROP 1 LAST SCH_TITLE SKYLAKE - SKT1 - 7 OF 21
J 0
(-7950 50);
DISPLAY 1.212766 (-7950 50);
PAINT GREEN (-7950 50);
FORCEPROP 2 LAST PAGE_BORDER TRUE
J 0
(-7890 5250);
DISPLAY 0.851064 (-7890 5250);
PAINT PINK (-7890 5250);
DISPLAY INVISIBLE (-7890 5250);
FORCEPROP 2 LAST CDS_LIB mstr_symbols
J 0
(0 0);
PAINT ORANGE (0 0);
DISPLAY INVISIBLE (0 0);
FORCEPROP 1 LAST COMMENT_BODY TRUE
J 0
(12 12);
DISPLAY 0.638298 (12 12);
PAINT GREEN (12 12);
DISPLAY INVISIBLE (12 12);
FORCEPROP 2 LAST CDS_XR_PAGE_TITLE CR-61 : @BASEBOARD_FAB2_LIB.BASEBOARD_FAB2(SCH_1):PAGE61
J 0
(-7890 5250);
DISPLAY 0.638298 (-7890 5250);
PAINT PINK (-7890 5250);
DISPLAY INVISIBLE (-7890 5250);
WIRE 17 -1 (-2800 3850)(-2800 3900);
WIRE 17 -1 (-2800 3900)(-2800 3950);
WIRE 17 -1 (-2800 3950)(-2800 4000);
WIRE 17 -1 (-2800 4000)(-2800 4050);
WIRE 17 -1 (-2800 4050)(-2800 4100);
WIRE 17 -1 (-2800 4100)(-2800 4150);
WIRE 17 -1 (-2800 4150)(-2800 4200);
WIRE 17 -1 (-2800 4200)(-2800 4250);
WIRE 17 -1 (-2800 4250)(-2800 4300);
WIRE 17 -1 (-2800 4300)(-2800 4350);
WIRE 17 -1 (-2800 4350)(-2800 4400);
WIRE 17 -1 (-2800 4400)(-2800 4450);
WIRE 17 -1 (-2800 4450)(-2800 4500);
WIRE 17 -1 (-2800 4500)(-2800 4550);
WIRE 17 -1 (-2800 4550)(-2800 4600);
WIRE 17 -1 (-2800 4600)(-2800 4650);
WIRE 17 -1 (-2050 4750)(-2800 4750);
FORCEPROP 2 LAST SIG_NAME M_L_DQS_DP<17:0>
J 0
(-2700 4760);
DISPLAY 0.617021 (-2700 4760);
PAINT ORANGE (-2700 4760);
WIRE 17 -1 (-2800 4650)(-2800 4700);
WIRE 17 -1 (-2800 4700)(-2800 4750);
WIRE 17 -1 (-2800 2900)(-2800 2950);
WIRE 17 -1 (-2800 2950)(-2800 3000);
WIRE 17 -1 (-2800 3000)(-2800 3050);
WIRE 17 -1 (-2800 3050)(-2800 3100);
WIRE 17 -1 (-2800 3100)(-2800 3150);
WIRE 17 -1 (-2800 3150)(-2800 3200);
WIRE 17 -1 (-2800 3200)(-2800 3250);
WIRE 17 -1 (-2800 3250)(-2800 3300);
WIRE 17 -1 (-2800 3300)(-2800 3350);
WIRE 17 -1 (-2800 3350)(-2800 3400);
WIRE 17 -1 (-2800 3400)(-2800 3450);
WIRE 17 -1 (-2800 3450)(-2800 3500);
WIRE 17 -1 (-2800 3500)(-2800 3550);
WIRE 17 -1 (-2800 3550)(-2800 3600);
WIRE 17 -1 (-2800 3600)(-2800 3650);
WIRE 17 -1 (-2800 3650)(-2800 3700);
WIRE 17 -1 (-2050 3775)(-2800 3775);
FORCEPROP 2 LAST SIG_NAME M_L_DQS_DN<17:0>
J 0
(-2700 3785);
DISPLAY 0.617021 (-2700 3785);
PAINT ORANGE (-2700 3785);
WIRE 17 -1 (-2800 3700)(-2800 3750);
WIRE 17 -1 (-2800 3750)(-2800 3775);
WIRE 17 -1 (-2800 1950)(-2800 2000);
WIRE 17 -1 (-2800 2000)(-2800 2050);
WIRE 17 -1 (-2800 2050)(-2800 2100);
WIRE 17 -1 (-2800 2100)(-2800 2150);
WIRE 17 -1 (-2800 2150)(-2800 2200);
WIRE 17 -1 (-2800 2200)(-2800 2250);
WIRE 17 -1 (-2800 2250)(-2800 2300);
WIRE 17 -1 (-2800 2300)(-2800 2350);
WIRE 17 -1 (-2800 2350)(-2800 2400);
WIRE 17 -1 (-2800 2400)(-2800 2450);
WIRE 17 -1 (-2800 2450)(-2800 2500);
WIRE 17 -1 (-2800 2500)(-2800 2550);
WIRE 17 -1 (-2800 2550)(-2800 2600);
WIRE 17 -1 (-2800 2600)(-2800 2650);
WIRE 17 -1 (-2800 2650)(-2800 2700);
WIRE 17 -1 (-2800 2700)(-2800 2750);
WIRE 17 -1 (-2050 2825)(-2800 2825);
FORCEPROP 2 LAST SIG_NAME M_L_MA<17:0>
J 0
(-2700 2835);
DISPLAY 0.617021 (-2700 2835);
PAINT ORANGE (-2700 2835);
WIRE 17 -1 (-2800 2750)(-2800 2800);
WIRE 17 -1 (-2800 2800)(-2800 2825);
WIRE 17 -1 (-2050 825)(-2800 825);
FORCEPROP 2 LAST SIG_NAME M_L_BA<1:0>
J 0
(-2700 835);
DISPLAY 0.617021 (-2700 835);
PAINT ORANGE (-2700 835);
WIRE 17 -1 (-2800 750)(-2800 800);
WIRE 17 -1 (-2800 800)(-2800 825);
WIRE 17 -1 (-2050 925)(-2800 925);
FORCEPROP 2 LAST SIG_NAME M_L_BG<1:0>
J 0
(-2700 935);
DISPLAY 0.617021 (-2700 935);
PAINT ORANGE (-2700 935);
WIRE 17 -1 (-2800 900)(-2800 925);
WIRE 17 -1 (-2800 850)(-2800 900);
WIRE 17 -1 (-2800 1700)(-2800 1750);
WIRE 17 -1 (-2800 1750)(-2800 1800);
WIRE 17 -1 (-2050 1875)(-2800 1875);
FORCEPROP 2 LAST SIG_NAME M_L_CKE<3:0>
J 0
(-2700 1885);
DISPLAY 0.617021 (-2700 1885);
PAINT ORANGE (-2700 1885);
WIRE 17 -1 (-2800 1800)(-2800 1850);
WIRE 17 -1 (-2800 1850)(-2800 1875);
WIRE 17 -1 (-2800 1000)(-2800 1050);
WIRE 17 -1 (-2800 1050)(-2800 1100);
WIRE 17 -1 (-2800 1100)(-2800 1150);
WIRE 17 -1 (-2800 1150)(-2800 1200);
WIRE 17 -1 (-2800 1200)(-2800 1250);
WIRE 17 -1 (-2800 1250)(-2800 1300);
WIRE 17 -1 (-2050 1375)(-2800 1375);
FORCEPROP 2 LAST SIG_NAME M_L_CS_N<7:0>
J 0
(-2700 1385);
DISPLAY 0.617021 (-2700 1385);
PAINT ORANGE (-2700 1385);
WIRE 17 -1 (-2800 1300)(-2800 1350);
WIRE 17 -1 (-2800 1350)(-2800 1375);
WIRE 17 -1 (-2800 1450)(-2800 1500);
WIRE 17 -1 (-2800 1500)(-2800 1550);
WIRE 17 -1 (-2050 1625)(-2800 1625);
FORCEPROP 2 LAST SIG_NAME M_L_ODT<3:0>
J 0
(-2700 1635);
DISPLAY 0.617021 (-2700 1635);
PAINT ORANGE (-2700 1635);
WIRE 17 -1 (-2800 1550)(-2800 1600);
WIRE 17 -1 (-2800 1600)(-2800 1625);
WIRE 17 -1 (-5625 1550)(-5625 1600);
WIRE 17 -1 (-5625 1600)(-5625 1650);
WIRE 17 -1 (-5625 1650)(-5625 1700);
WIRE 17 -1 (-5625 1700)(-5625 1750);
WIRE 17 -1 (-5625 1750)(-5625 1800);
WIRE 17 -1 (-5625 1800)(-5625 1850);
WIRE 17 -1 (-5625 1850)(-5625 1900);
WIRE 17 -1 (-5625 1900)(-5625 1950);
WIRE 17 -1 (-5625 1950)(-5625 2000);
WIRE 17 -1 (-5625 2000)(-5625 2050);
WIRE 17 -1 (-5625 2050)(-5625 2100);
WIRE 17 -1 (-5625 2100)(-5625 2150);
WIRE 17 -1 (-5625 2150)(-5625 2200);
WIRE 17 -1 (-5625 2200)(-5625 2250);
WIRE 17 -1 (-5625 2250)(-5625 2300);
WIRE 17 -1 (-5625 2300)(-5625 2350);
WIRE 17 -1 (-5625 2350)(-5625 2400);
WIRE 17 -1 (-5625 2400)(-5625 2450);
WIRE 17 -1 (-5625 2450)(-5625 2500);
WIRE 17 -1 (-5625 2500)(-5625 2550);
WIRE 17 -1 (-5625 2550)(-5625 2600);
WIRE 17 -1 (-5625 2600)(-5625 2650);
WIRE 17 -1 (-5625 2650)(-5625 2700);
WIRE 17 -1 (-5625 2700)(-5625 2750);
WIRE 17 -1 (-5625 2750)(-5625 2800);
WIRE 17 -1 (-5625 2800)(-5625 2850);
WIRE 17 -1 (-5625 2850)(-5625 2900);
WIRE 17 -1 (-5625 2900)(-5625 2950);
WIRE 17 -1 (-5625 2950)(-5625 3000);
WIRE 17 -1 (-5625 3000)(-5625 3050);
WIRE 17 -1 (-5625 3050)(-5625 3100);
WIRE 17 -1 (-5625 3100)(-5625 3150);
WIRE 17 -1 (-5625 3150)(-5625 3200);
WIRE 17 -1 (-5625 3200)(-5625 3250);
WIRE 17 -1 (-5625 3250)(-5625 3300);
WIRE 17 -1 (-5625 3300)(-5625 3350);
WIRE 17 -1 (-5625 3350)(-5625 3400);
WIRE 17 -1 (-5625 3400)(-5625 3450);
WIRE 17 -1 (-5625 3450)(-5625 3500);
WIRE 17 -1 (-5625 3500)(-5625 3550);
WIRE 17 -1 (-5625 3550)(-5625 3600);
WIRE 17 -1 (-5625 3600)(-5625 3650);
WIRE 17 -1 (-5625 3650)(-5625 3700);
WIRE 17 -1 (-5625 3700)(-5625 3750);
WIRE 17 -1 (-5625 3750)(-5625 3800);
WIRE 17 -1 (-5625 3800)(-5625 3850);
WIRE 17 -1 (-5625 3850)(-5625 3900);
WIRE 17 -1 (-5625 3900)(-5625 3950);
WIRE 17 -1 (-5625 3950)(-5625 4000);
WIRE 17 -1 (-5625 4000)(-5625 4050);
WIRE 17 -1 (-5625 4050)(-5625 4100);
WIRE 17 -1 (-5625 4100)(-5625 4150);
WIRE 17 -1 (-5625 4150)(-5625 4200);
WIRE 17 -1 (-5625 4200)(-5625 4250);
WIRE 17 -1 (-5625 4250)(-5625 4300);
WIRE 17 -1 (-5625 4300)(-5625 4350);
WIRE 17 -1 (-5625 4350)(-5625 4400);
WIRE 17 -1 (-5625 4400)(-5625 4450);
WIRE 17 -1 (-5625 4450)(-5625 4500);
WIRE 17 -1 (-5625 4500)(-5625 4550);
WIRE 17 -1 (-5625 4550)(-5625 4600);
WIRE 17 -1 (-5625 4600)(-5625 4650);
WIRE 17 -1 (-5625 4800)(-6375 4800);
FORCEPROP 2 LAST SIG_NAME M_L_DQ<63:0>
J 0
(-6325 4810);
DISPLAY 0.617021 (-6325 4810);
PAINT ORANGE (-6325 4810);
WIRE 17 -1 (-5625 4650)(-5625 4700);
WIRE 17 -1 (-5625 4700)(-5625 4800);
WIRE 17 -1 (-5625 650)(-5625 700);
WIRE 17 -1 (-5625 700)(-5625 750);
WIRE 17 -1 (-5625 825)(-6375 825);
FORCEPROP 2 LAST SIG_NAME M_L_CLK_DN<3:0>
J 0
(-6325 835);
DISPLAY 0.617021 (-6325 835);
PAINT ORANGE (-6325 835);
WIRE 17 -1 (-5625 750)(-5625 800);
WIRE 17 -1 (-5625 800)(-5625 825);
WIRE 17 -1 (-5625 850)(-5625 900);
WIRE 17 -1 (-5625 900)(-5625 950);
WIRE 17 -1 (-5625 1025)(-6375 1025);
FORCEPROP 2 LAST SIG_NAME M_L_CLK_DP<3:0>
J 0
(-6325 1035);
DISPLAY 0.617021 (-6325 1035);
PAINT ORANGE (-6325 1035);
WIRE 17 -1 (-5625 950)(-5625 1000);
WIRE 17 -1 (-5625 1000)(-5625 1025);
WIRE 17 -1 (-5625 1100)(-5625 1150);
WIRE 17 -1 (-5625 1150)(-5625 1200);
WIRE 17 -1 (-5625 1200)(-5625 1250);
WIRE 17 -1 (-5625 1250)(-5625 1300);
WIRE 17 -1 (-5625 1300)(-5625 1350);
WIRE 17 -1 (-5625 1350)(-5625 1400);
WIRE 17 -1 (-5625 1475)(-6375 1475);
FORCEPROP 2 LAST SIG_NAME M_L_ECC<7:0>
J 0
(-6325 1485);
DISPLAY 0.617021 (-6325 1485);
PAINT ORANGE (-6325 1485);
WIRE 17 -1 (-5625 1400)(-5625 1450);
WIRE 17 -1 (-5625 1450)(-5625 1475);
WIRE 16 -1 (-5025 4275)(-5525 4275);
WIRE 16 -1 (-5025 1125)(-5525 1125);
WIRE 16 -1 (-5525 3575)(-5025 3575);
WIRE 16 -1 (-5025 4125)(-5525 4125);
WIRE 16 -1 (-3325 1525)(-2900 1525);
WIRE 16 -1 (-5525 3225)(-5025 3225);
WIRE 16 -1 (-3325 2875)(-2900 2875);
WIRE 16 -1 (-5025 525)(-6375 525);
FORCEPROP 2 LAST SIG_NAME M_L_C<2>
J 0
(-6325 535);
DISPLAY 0.617021 (-6325 535);
PAINT ORANGE (-6325 535);
WIRE 16 -1 (-5025 1075)(-5525 1075);
WIRE 16 -1 (-5025 1175)(-5525 1175);
WIRE 16 -1 (-5025 1225)(-5525 1225);
WIRE 16 -1 (-5025 1275)(-5525 1275);
WIRE 16 -1 (-5025 1325)(-5525 1325);
WIRE 16 -1 (-5025 1375)(-5525 1375);
WIRE 16 -1 (-5025 1425)(-5525 1425);
WIRE 16 -1 (-5525 1525)(-5025 1525);
WIRE 16 -1 (-5525 1575)(-5025 1575);
WIRE 16 -1 (-5525 1625)(-5025 1625);
WIRE 16 -1 (-5025 1675)(-5525 1675);
WIRE 16 -1 (-5525 1725)(-5025 1725);
WIRE 16 -1 (-5525 1775)(-5025 1775);
WIRE 16 -1 (-5025 1825)(-5525 1825);
WIRE 16 -1 (-5525 1875)(-5025 1875);
WIRE 16 -1 (-5525 1925)(-5025 1925);
WIRE 16 -1 (-5525 1975)(-5025 1975);
WIRE 16 -1 (-5525 2025)(-5025 2025);
WIRE 16 -1 (-5025 825)(-5525 825);
WIRE 16 -1 (-5025 875)(-5525 875);
WIRE 16 -1 (-5025 925)(-5525 925);
WIRE 16 -1 (-5025 975)(-5525 975);
WIRE 16 -1 (-5025 625)(-5525 625);
WIRE 16 -1 (-5025 675)(-5525 675);
WIRE 16 -1 (-5025 725)(-5525 725);
WIRE 16 -1 (-5025 775)(-5525 775);
WIRE 16 -1 (-5525 2075)(-5025 2075);
WIRE 16 -1 (-5525 2125)(-5025 2125);
WIRE 16 -1 (-5525 2175)(-5025 2175);
WIRE 16 -1 (-5525 2225)(-5025 2225);
WIRE 16 -1 (-5025 2275)(-5525 2275);
WIRE 16 -1 (-5525 2325)(-5025 2325);
WIRE 16 -1 (-5525 2375)(-5025 2375);
WIRE 16 -1 (-5025 2425)(-5525 2425);
WIRE 16 -1 (-5525 2475)(-5025 2475);
WIRE 16 -1 (-5525 2525)(-5025 2525);
WIRE 16 -1 (-5525 2575)(-5025 2575);
WIRE 16 -1 (-5525 2625)(-5025 2625);
WIRE 16 -1 (-5025 2675)(-5525 2675);
WIRE 16 -1 (-5525 2725)(-5025 2725);
WIRE 16 -1 (-5525 2775)(-5025 2775);
WIRE 16 -1 (-5525 2825)(-5025 2825);
WIRE 16 -1 (-5525 2875)(-5025 2875);
WIRE 16 -1 (-5525 2925)(-5025 2925);
WIRE 16 -1 (-5525 2975)(-5025 2975);
WIRE 16 -1 (-5025 3025)(-5525 3025);
WIRE 16 -1 (-5525 3075)(-5025 3075);
WIRE 16 -1 (-5525 3125)(-5025 3125);
WIRE 16 -1 (-5525 3175)(-5025 3175);
WIRE 16 -1 (-5525 3275)(-5025 3275);
WIRE 16 -1 (-5525 3325)(-5025 3325);
WIRE 16 -1 (-5025 3375)(-5525 3375);
WIRE 16 -1 (-5525 3425)(-5025 3425);
WIRE 16 -1 (-5525 3475)(-5025 3475);
WIRE 16 -1 (-5025 3525)(-5525 3525);
WIRE 16 -1 (-5525 3625)(-5025 3625);
WIRE 16 -1 (-5025 3675)(-5525 3675);
WIRE 16 -1 (-5025 3725)(-5525 3725);
WIRE 16 -1 (-5025 3775)(-5525 3775);
WIRE 16 -1 (-5025 3825)(-5525 3825);
WIRE 16 -1 (-5025 3875)(-5525 3875);
WIRE 16 -1 (-5025 3925)(-5525 3925);
WIRE 16 -1 (-5025 3975)(-5525 3975);
WIRE 16 -1 (-5025 4025)(-5525 4025);
WIRE 16 -1 (-5025 4075)(-5525 4075);
WIRE 16 -1 (-5025 4175)(-5525 4175);
WIRE 16 -1 (-5025 4225)(-5525 4225);
WIRE 16 -1 (-5025 4325)(-5525 4325);
WIRE 16 -1 (-5025 4375)(-5525 4375);
WIRE 16 -1 (-5025 4425)(-5525 4425);
WIRE 16 -1 (-5025 4475)(-5525 4475);
WIRE 16 -1 (-5025 4525)(-5525 4525);
WIRE 16 -1 (-5025 4575)(-5525 4575);
WIRE 16 -1 (-5025 4625)(-5525 4625);
WIRE 16 -1 (-5025 4675)(-5525 4675);
WIRE 16 -1 (-3325 1425)(-2900 1425);
WIRE 16 -1 (-3325 1475)(-2900 1475);
WIRE 16 -1 (-3325 1575)(-2900 1575);
WIRE 16 -1 (-3325 1925)(-2900 1925);
WIRE 16 -1 (-3325 1975)(-2900 1975);
WIRE 16 -1 (-3325 2025)(-2900 2025);
WIRE 16 -1 (-3325 975)(-2900 975);
WIRE 16 -1 (-3325 1025)(-2900 1025);
WIRE 16 -1 (-3325 1075)(-2900 1075);
WIRE 16 -1 (-3325 1125)(-2900 1125);
WIRE 16 -1 (-3325 1175)(-2900 1175);
WIRE 16 -1 (-3325 1225)(-2900 1225);
WIRE 16 -1 (-3325 1275)(-2900 1275);
WIRE 16 -1 (-3325 1325)(-2900 1325);
WIRE 16 -1 (-3325 1675)(-2900 1675);
WIRE 16 -1 (-3325 1725)(-2900 1725);
WIRE 16 -1 (-3325 1775)(-2900 1775);
WIRE 16 -1 (-3325 1825)(-2900 1825);
WIRE 16 -1 (-3325 825)(-2900 825);
WIRE 16 -1 (-3325 875)(-2900 875);
WIRE 16 -1 (-3325 725)(-2900 725);
WIRE 16 -1 (-3325 775)(-2900 775);
WIRE 16 -1 (-3325 2075)(-2900 2075);
WIRE 16 -1 (-3325 2125)(-2900 2125);
WIRE 16 -1 (-3325 2175)(-2900 2175);
WIRE 16 -1 (-3325 2225)(-2900 2225);
WIRE 16 -1 (-3325 2275)(-2900 2275);
WIRE 16 -1 (-3325 2325)(-2900 2325);
WIRE 16 -1 (-3325 2375)(-2900 2375);
WIRE 16 -1 (-3325 2425)(-2900 2425);
WIRE 16 -1 (-3325 2475)(-2900 2475);
WIRE 16 -1 (-3325 2525)(-2900 2525);
WIRE 16 -1 (-3325 2575)(-2900 2575);
WIRE 16 -1 (-3325 2625)(-2900 2625);
WIRE 16 -1 (-3325 2675)(-2900 2675);
WIRE 16 -1 (-3325 2725)(-2900 2725);
WIRE 16 -1 (-3325 2775)(-2900 2775);
WIRE 16 -1 (-3325 3825)(-2900 3825);
WIRE 16 -1 (-3325 3875)(-2900 3875);
WIRE 16 -1 (-3325 3925)(-2900 3925);
WIRE 16 -1 (-3325 3975)(-2900 3975);
WIRE 16 -1 (-3325 4025)(-2900 4025);
WIRE 16 -1 (-3325 4075)(-2900 4075);
WIRE 16 -1 (-3325 2925)(-2900 2925);
WIRE 16 -1 (-3325 2975)(-2900 2975);
WIRE 16 -1 (-3325 3025)(-2900 3025);
WIRE 16 -1 (-3325 3075)(-2900 3075);
WIRE 16 -1 (-3325 3125)(-2900 3125);
WIRE 16 -1 (-3325 3175)(-2900 3175);
WIRE 16 -1 (-3325 3225)(-2900 3225);
WIRE 16 -1 (-3325 3275)(-2900 3275);
WIRE 16 -1 (-3325 3325)(-2900 3325);
WIRE 16 -1 (-3325 3375)(-2900 3375);
WIRE 16 -1 (-3325 3425)(-2900 3425);
WIRE 16 -1 (-3325 3475)(-2900 3475);
WIRE 16 -1 (-3325 3525)(-2900 3525);
WIRE 16 -1 (-3325 3575)(-2900 3575);
WIRE 16 -1 (-3325 3625)(-2900 3625);
WIRE 16 -1 (-3325 3675)(-2900 3675);
WIRE 16 -1 (-3325 3725)(-2900 3725);
WIRE 16 -1 (-2025 525)(-3325 525);
FORCEPROP 2 LAST SIG_NAME M_L_PAR
J 0
(-2700 535);
DISPLAY 0.617021 (-2700 535);
PAINT ORANGE (-2700 535);
WIRE 16 -1 (-2025 575)(-3325 575);
FORCEPROP 2 LAST SIG_NAME M_L_ALERT_N
J 0
(-2700 585);
DISPLAY 0.617021 (-2700 585);
PAINT ORANGE (-2700 585);
WIRE 16 -1 (-2025 625)(-3325 625);
FORCEPROP 2 LAST SIG_NAME M_L_ACT_N
J 0
(-2700 635);
DISPLAY 0.617021 (-2700 635);
PAINT ORANGE (-2700 635);
WIRE 16 -1 (-3325 4125)(-2900 4125);
WIRE 16 -1 (-3325 4175)(-2900 4175);
WIRE 16 -1 (-3325 4225)(-2900 4225);
WIRE 16 -1 (-3325 4275)(-2900 4275);
WIRE 16 -1 (-3325 4325)(-2900 4325);
WIRE 16 -1 (-3325 4375)(-2900 4375);
WIRE 16 -1 (-3325 4425)(-2900 4425);
WIRE 16 -1 (-3325 4475)(-2900 4475);
WIRE 16 -1 (-3325 4525)(-2900 4525);
WIRE 16 -1 (-3325 4575)(-2900 4575);
WIRE 16 -1 (-3325 4625)(-2900 4625);
WIRE 16 -1 (-3325 4675)(-2900 4675);
FORCENOTE
ROOM=CPU1
(-7925 375) 0;
DISPLAY LEFT (-7925 375);
DISPLAY 1.723404 (-7925 375);
PAINT PURPLE (-7925 375);
FORCENOTE
BOM_COST=PROC_SOCKET
(-7925 250) 0;
DISPLAY LEFT (-7925 250);
DISPLAY 1.723404 (-7925 250);
PAINT PURPLE (-7925 250);
QUIT
